FILE_TYPE = MACRO_DRAWING;
SET COLOR_WIRE YELLOW;
SET COLOR_PROP ORANGE;
SET COLOR_DOT WHITE;
SET COLOR_ARC YELLOW;
SET COLOR_BODY GREEN;
SET COLOR_NOTE PURPLE;
SET PROP_DISPLAY VALUE;
SET PAGE_NUMBER P15;
FORCEADD GENOA_SP5..6
(-4650 3600);
FORCEPROP 1 LAST LOCATION U25
J 0
(-5295 6431);
DISPLAY 0.489362 (-5295 6431);
PAINT SKYBLUE (-5295 6431);
FORCEPROP 0 LAST $SEC 6
J 0
(-5275 6475);
DISPLAY 0.680851 (-5275 6475);
PAINT MONO (-5275 6475);
DISPLAY INVISIBLE (-5275 6475);
FORCEPROP 0 LAST CDS_SEC 6
J 0
(-5300 6400);
DISPLAY 1.021277 (-5300 6400);
DISPLAY INVISIBLE (-5300 6400);
FORCEPROP 0 LASTPIN (-5450 2975) $PN BC67
J 2
(-5460 2985);
DISPLAY 0.489362 (-5460 2985);
PAINT MONO (-5460 2985);
FORCEPROP 0 LASTPIN (-5450 2925) $PN BD67
J 2
(-5460 2935);
DISPLAY 0.489362 (-5460 2935);
PAINT MONO (-5460 2935);
FORCEPROP 0 LASTPIN (-5450 1825) $PN BF67
J 2
(-5460 1835);
DISPLAY 0.489362 (-5460 1835);
PAINT MONO (-5460 1835);
FORCEPROP 0 LASTPIN (-5450 1775) $PN BG67
J 2
(-5460 1785);
DISPLAY 0.489362 (-5460 1785);
PAINT MONO (-5460 1785);
FORCEPROP 0 LASTPIN (-5450 2125) $PN AT65
J 2
(-5460 2135);
DISPLAY 0.489362 (-5460 2135);
PAINT MONO (-5460 2135);
FORCEPROP 0 LASTPIN (-5450 2025) $PN AU66
J 2
(-5460 2035);
DISPLAY 0.489362 (-5460 2035);
PAINT MONO (-5460 2035);
FORCEPROP 0 LASTPIN (-5450 2825) $PN AV67
J 2
(-5460 2835);
DISPLAY 0.489362 (-5460 2835);
PAINT MONO (-5460 2835);
FORCEPROP 0 LASTPIN (-5450 2775) $PN AW66
J 2
(-5460 2785);
DISPLAY 0.489362 (-5460 2785);
PAINT MONO (-5460 2785);
FORCEPROP 0 LASTPIN (-5450 2675) $PN BN66
J 2
(-5460 2685);
DISPLAY 0.489362 (-5460 2685);
PAINT MONO (-5460 2685);
FORCEPROP 0 LASTPIN (-5450 1675) $PN AU67
J 2
(-5460 1685);
DISPLAY 0.489362 (-5460 1685);
PAINT MONO (-5460 1685);
FORCEPROP 0 LASTPIN (-5450 1625) $PN AV65
J 2
(-5460 1635);
DISPLAY 0.489362 (-5460 1635);
PAINT MONO (-5460 1635);
FORCEPROP 0 LASTPIN (-5450 1525) $PN BP65
J 2
(-5460 1535);
DISPLAY 0.489362 (-5460 1535);
PAINT MONO (-5460 1535);
FORCEPROP 0 LASTPIN (-5450 3825) $PN AW67
J 2
(-5460 3835);
DISPLAY 0.489362 (-5460 3835);
PAINT MONO (-5460 3835);
FORCEPROP 0 LASTPIN (-5450 3775) $PN AY67
J 2
(-5460 3785);
DISPLAY 0.489362 (-5460 3785);
PAINT MONO (-5460 3785);
FORCEPROP 0 LASTPIN (-5450 3725) $PN AY65
J 2
(-5460 3735);
DISPLAY 0.489362 (-5460 3735);
PAINT MONO (-5460 3735);
FORCEPROP 0 LASTPIN (-5450 3675) $PN BA66
J 2
(-5460 3685);
DISPLAY 0.489362 (-5460 3685);
PAINT MONO (-5460 3685);
FORCEPROP 0 LASTPIN (-5450 3625) $PN BA67
J 2
(-5460 3635);
DISPLAY 0.489362 (-5460 3635);
PAINT MONO (-5460 3635);
FORCEPROP 0 LASTPIN (-5450 3575) $PN BB67
J 2
(-5460 3585);
DISPLAY 0.489362 (-5460 3585);
PAINT MONO (-5460 3585);
FORCEPROP 0 LASTPIN (-5450 3525) $PN BB65
J 2
(-5460 3535);
DISPLAY 0.489362 (-5460 3535);
PAINT MONO (-5460 3535);
FORCEPROP 0 LASTPIN (-3850 2375) $PN AJ67
J 0
(-3840 2385);
DISPLAY 0.489362 (-3840 2385);
PAINT MONO (-3840 2385);
FORCEPROP 0 LASTPIN (-3850 2325) $PN AK65
J 0
(-3840 2335);
DISPLAY 0.489362 (-3840 2335);
PAINT MONO (-3840 2335);
FORCEPROP 0 LASTPIN (-3850 2275) $PN AK67
J 0
(-3840 2285);
DISPLAY 0.489362 (-3840 2285);
PAINT MONO (-3840 2285);
FORCEPROP 0 LASTPIN (-3850 2225) $PN AL66
J 0
(-3840 2235);
DISPLAY 0.489362 (-3840 2235);
PAINT MONO (-3840 2235);
FORCEPROP 0 LASTPIN (-3850 2175) $PN AN67
J 0
(-3840 2185);
DISPLAY 0.489362 (-3840 2185);
PAINT MONO (-3840 2185);
FORCEPROP 0 LASTPIN (-3850 2125) $PN AP65
J 0
(-3840 2135);
DISPLAY 0.489362 (-3840 2135);
PAINT MONO (-3840 2135);
FORCEPROP 0 LASTPIN (-3850 2075) $PN AP67
J 0
(-3840 2085);
DISPLAY 0.489362 (-3840 2085);
PAINT MONO (-3840 2085);
FORCEPROP 0 LASTPIN (-3850 2025) $PN AR66
J 0
(-3840 2035);
DISPLAY 0.489362 (-3840 2035);
PAINT MONO (-3840 2035);
FORCEPROP 0 LASTPIN (-3850 5975) $PN E67
J 0
(-3840 5985);
DISPLAY 0.489362 (-3840 5985);
PAINT MONO (-3840 5985);
FORCEPROP 0 LASTPIN (-3850 5925) $PN F65
J 0
(-3840 5935);
DISPLAY 0.489362 (-3840 5935);
PAINT MONO (-3840 5935);
FORCEPROP 0 LASTPIN (-3850 5875) $PN F67
J 0
(-3840 5885);
DISPLAY 0.489362 (-3840 5885);
PAINT MONO (-3840 5885);
FORCEPROP 0 LASTPIN (-3850 5825) $PN G66
J 0
(-3840 5835);
DISPLAY 0.489362 (-3840 5835);
PAINT MONO (-3840 5835);
FORCEPROP 0 LASTPIN (-3850 5775) $PN J67
J 0
(-3840 5785);
DISPLAY 0.489362 (-3840 5785);
PAINT MONO (-3840 5785);
FORCEPROP 0 LASTPIN (-3850 5725) $PN K65
J 0
(-3840 5735);
DISPLAY 0.489362 (-3840 5735);
PAINT MONO (-3840 5735);
FORCEPROP 0 LASTPIN (-3850 5675) $PN K67
J 0
(-3840 5685);
DISPLAY 0.489362 (-3840 5685);
PAINT MONO (-3840 5685);
FORCEPROP 0 LASTPIN (-3850 5625) $PN L66
J 0
(-3840 5635);
DISPLAY 0.489362 (-3840 5635);
PAINT MONO (-3840 5635);
FORCEPROP 0 LASTPIN (-3850 5525) $PN L67
J 0
(-3840 5535);
DISPLAY 0.489362 (-3840 5535);
PAINT MONO (-3840 5535);
FORCEPROP 0 LASTPIN (-3850 5475) $PN M65
J 0
(-3840 5485);
DISPLAY 0.489362 (-3840 5485);
PAINT MONO (-3840 5485);
FORCEPROP 0 LASTPIN (-3850 5425) $PN M67
J 0
(-3840 5435);
DISPLAY 0.489362 (-3840 5435);
PAINT MONO (-3840 5435);
FORCEPROP 0 LASTPIN (-3850 5375) $PN N66
J 0
(-3840 5385);
DISPLAY 0.489362 (-3840 5385);
PAINT MONO (-3840 5385);
FORCEPROP 0 LASTPIN (-3850 5325) $PN R67
J 0
(-3840 5335);
DISPLAY 0.489362 (-3840 5335);
PAINT MONO (-3840 5335);
FORCEPROP 0 LASTPIN (-3850 5275) $PN T65
J 0
(-3840 5285);
DISPLAY 0.489362 (-3840 5285);
PAINT MONO (-3840 5285);
FORCEPROP 0 LASTPIN (-3850 5225) $PN T67
J 0
(-3840 5235);
DISPLAY 0.489362 (-3840 5235);
PAINT MONO (-3840 5235);
FORCEPROP 0 LASTPIN (-3850 5175) $PN U66
J 0
(-3840 5185);
DISPLAY 0.489362 (-3840 5185);
PAINT MONO (-3840 5185);
FORCEPROP 0 LASTPIN (-3850 5075) $PN U67
J 0
(-3840 5085);
DISPLAY 0.489362 (-3840 5085);
PAINT MONO (-3840 5085);
FORCEPROP 0 LASTPIN (-3850 5025) $PN V65
J 0
(-3840 5035);
DISPLAY 0.489362 (-3840 5035);
PAINT MONO (-3840 5035);
FORCEPROP 0 LASTPIN (-3850 4975) $PN V67
J 0
(-3840 4985);
DISPLAY 0.489362 (-3840 4985);
PAINT MONO (-3840 4985);
FORCEPROP 0 LASTPIN (-3850 4925) $PN W66
J 0
(-3840 4935);
DISPLAY 0.489362 (-3840 4935);
PAINT MONO (-3840 4935);
FORCEPROP 0 LASTPIN (-3850 4875) $PN AA67
J 0
(-3840 4885);
DISPLAY 0.489362 (-3840 4885);
PAINT MONO (-3840 4885);
FORCEPROP 0 LASTPIN (-3850 4825) $PN AB65
J 0
(-3840 4835);
DISPLAY 0.489362 (-3840 4835);
PAINT MONO (-3840 4835);
FORCEPROP 0 LASTPIN (-3850 4775) $PN AB67
J 0
(-3840 4785);
DISPLAY 0.489362 (-3840 4785);
PAINT MONO (-3840 4785);
FORCEPROP 0 LASTPIN (-3850 4725) $PN AC66
J 0
(-3840 4735);
DISPLAY 0.489362 (-3840 4735);
PAINT MONO (-3840 4735);
FORCEPROP 0 LASTPIN (-3850 4625) $PN AC67
J 0
(-3840 4635);
DISPLAY 0.489362 (-3840 4635);
PAINT MONO (-3840 4635);
FORCEPROP 0 LASTPIN (-3850 4575) $PN AD65
J 0
(-3840 4585);
DISPLAY 0.489362 (-3840 4585);
PAINT MONO (-3840 4585);
FORCEPROP 0 LASTPIN (-3850 4525) $PN AD67
J 0
(-3840 4535);
DISPLAY 0.489362 (-3840 4535);
PAINT MONO (-3840 4535);
FORCEPROP 0 LASTPIN (-3850 4475) $PN AE66
J 0
(-3840 4485);
DISPLAY 0.489362 (-3840 4485);
PAINT MONO (-3840 4485);
FORCEPROP 0 LASTPIN (-3850 4425) $PN AG67
J 0
(-3840 4435);
DISPLAY 0.489362 (-3840 4435);
PAINT MONO (-3840 4435);
FORCEPROP 0 LASTPIN (-3850 4375) $PN AH65
J 0
(-3840 4385);
DISPLAY 0.489362 (-3840 4385);
PAINT MONO (-3840 4385);
FORCEPROP 0 LASTPIN (-3850 4325) $PN AH67
J 0
(-3840 4335);
DISPLAY 0.489362 (-3840 4335);
PAINT MONO (-3840 4335);
FORCEPROP 0 LASTPIN (-3850 4275) $PN AJ66
J 0
(-3840 4285);
DISPLAY 0.489362 (-3840 4285);
PAINT MONO (-3840 4285);
FORCEPROP 0 LASTPIN (-5450 5975) $PN G67
J 2
(-5460 5985);
DISPLAY 0.489362 (-5460 5985);
PAINT MONO (-5460 5985);
FORCEPROP 0 LASTPIN (-5450 5875) $PN N67
J 2
(-5460 5885);
DISPLAY 0.489362 (-5460 5885);
PAINT MONO (-5460 5885);
FORCEPROP 0 LASTPIN (-5450 5775) $PN W67
J 2
(-5460 5785);
DISPLAY 0.489362 (-5460 5785);
PAINT MONO (-5460 5785);
FORCEPROP 0 LASTPIN (-5450 5675) $PN AE67
J 2
(-5460 5685);
DISPLAY 0.489362 (-5460 5685);
PAINT MONO (-5460 5685);
FORCEPROP 0 LASTPIN (-5450 5575) $PN AL67
J 2
(-5460 5585);
DISPLAY 0.489362 (-5460 5585);
PAINT MONO (-5460 5585);
FORCEPROP 0 LASTPIN (-5450 5475) $PN J66
J 2
(-5460 5485);
DISPLAY 0.489362 (-5460 5485);
PAINT MONO (-5460 5485);
FORCEPROP 0 LASTPIN (-5450 5375) $PN R66
J 2
(-5460 5385);
DISPLAY 0.489362 (-5460 5385);
PAINT MONO (-5460 5385);
FORCEPROP 0 LASTPIN (-5450 5275) $PN AA66
J 2
(-5460 5285);
DISPLAY 0.489362 (-5460 5285);
PAINT MONO (-5460 5285);
FORCEPROP 0 LASTPIN (-5450 5175) $PN AG66
J 2
(-5460 5185);
DISPLAY 0.489362 (-5460 5185);
PAINT MONO (-5460 5185);
FORCEPROP 0 LASTPIN (-5450 5075) $PN AN66
J 2
(-5460 5085);
DISPLAY 0.489362 (-5460 5085);
PAINT MONO (-5460 5085);
FORCEPROP 0 LASTPIN (-5450 5925) $PN H67
J 2
(-5460 5935);
DISPLAY 0.489362 (-5460 5935);
PAINT MONO (-5460 5935);
FORCEPROP 0 LASTPIN (-5450 5825) $PN P67
J 2
(-5460 5835);
DISPLAY 0.489362 (-5460 5835);
PAINT MONO (-5460 5835);
FORCEPROP 0 LASTPIN (-5450 5725) $PN Y67
J 2
(-5460 5735);
DISPLAY 0.489362 (-5460 5735);
PAINT MONO (-5460 5735);
FORCEPROP 0 LASTPIN (-5450 5625) $PN AF67
J 2
(-5460 5635);
DISPLAY 0.489362 (-5460 5635);
PAINT MONO (-5460 5635);
FORCEPROP 0 LASTPIN (-5450 5525) $PN AM67
J 2
(-5460 5535);
DISPLAY 0.489362 (-5460 5535);
PAINT MONO (-5460 5535);
FORCEPROP 0 LASTPIN (-5450 5425) $PN H65
J 2
(-5460 5435);
DISPLAY 0.489362 (-5460 5435);
PAINT MONO (-5460 5435);
FORCEPROP 0 LASTPIN (-5450 5325) $PN P65
J 2
(-5460 5335);
DISPLAY 0.489362 (-5460 5335);
PAINT MONO (-5460 5335);
FORCEPROP 0 LASTPIN (-5450 5225) $PN Y65
J 2
(-5460 5235);
DISPLAY 0.489362 (-5460 5235);
PAINT MONO (-5460 5235);
FORCEPROP 0 LASTPIN (-5450 5125) $PN AF65
J 2
(-5460 5135);
DISPLAY 0.489362 (-5460 5135);
PAINT MONO (-5460 5135);
FORCEPROP 0 LASTPIN (-5450 5025) $PN AM65
J 2
(-5460 5035);
DISPLAY 0.489362 (-5460 5035);
PAINT MONO (-5460 5035);
FORCEPROP 0 LASTPIN (-5450 2575) $PN BC66
J 2
(-5460 2585);
DISPLAY 0.489362 (-5460 2585);
PAINT MONO (-5460 2585);
FORCEPROP 0 LASTPIN (-5450 2475) $PN BM65
J 2
(-5460 2485);
DISPLAY 0.489362 (-5460 2485);
PAINT MONO (-5460 2485);
FORCEPROP 0 LASTPIN (-5450 2425) $PN BN67
J 2
(-5460 2435);
DISPLAY 0.489362 (-5460 2435);
PAINT MONO (-5460 2435);
FORCEPROP 0 LASTPIN (-5450 2325) $PN BP67
J 2
(-5460 2335);
DISPLAY 0.489362 (-5460 2335);
PAINT MONO (-5460 2335);
FORCEPROP 0 LASTPIN (-5450 1425) $PN BL66
J 2
(-5460 1435);
DISPLAY 0.489362 (-5460 1435);
PAINT MONO (-5460 1435);
FORCEPROP 0 LASTPIN (-5450 1375) $PN BM67
J 2
(-5460 1385);
DISPLAY 0.489362 (-5460 1385);
PAINT MONO (-5460 1385);
FORCEPROP 0 LASTPIN (-5450 1275) $PN BR67
J 2
(-5460 1285);
DISPLAY 0.489362 (-5460 1285);
PAINT MONO (-5460 1285);
FORCEPROP 0 LASTPIN (-5450 3425) $PN BG66
J 2
(-5460 3435);
DISPLAY 0.489362 (-5460 3435);
PAINT MONO (-5460 3435);
FORCEPROP 0 LASTPIN (-5450 3375) $PN BH65
J 2
(-5460 3385);
DISPLAY 0.489362 (-5460 3385);
PAINT MONO (-5460 3385);
FORCEPROP 0 LASTPIN (-5450 3325) $PN BH67
J 2
(-5460 3335);
DISPLAY 0.489362 (-5460 3335);
PAINT MONO (-5460 3335);
FORCEPROP 0 LASTPIN (-5450 3275) $PN BJ67
J 2
(-5460 3285);
DISPLAY 0.489362 (-5460 3285);
PAINT MONO (-5460 3285);
FORCEPROP 0 LASTPIN (-5450 3225) $PN BJ66
J 2
(-5460 3235);
DISPLAY 0.489362 (-5460 3235);
PAINT MONO (-5460 3235);
FORCEPROP 0 LASTPIN (-5450 3175) $PN BK65
J 2
(-5460 3185);
DISPLAY 0.489362 (-5460 3185);
PAINT MONO (-5460 3185);
FORCEPROP 0 LASTPIN (-5450 3125) $PN BK67
J 2
(-5460 3135);
DISPLAY 0.489362 (-5460 3135);
PAINT MONO (-5460 3135);
FORCEPROP 0 LASTPIN (-3850 1925) $PN BY67
J 0
(-3840 1935);
DISPLAY 0.489362 (-3840 1935);
PAINT MONO (-3840 1935);
FORCEPROP 0 LASTPIN (-3850 1875) $PN CA66
J 0
(-3840 1885);
DISPLAY 0.489362 (-3840 1885);
PAINT MONO (-3840 1885);
FORCEPROP 0 LASTPIN (-3850 1825) $PN CA67
J 0
(-3840 1835);
DISPLAY 0.489362 (-3840 1835);
PAINT MONO (-3840 1835);
FORCEPROP 0 LASTPIN (-3850 1775) $PN CB65
J 0
(-3840 1785);
DISPLAY 0.489362 (-3840 1785);
PAINT MONO (-3840 1785);
FORCEPROP 0 LASTPIN (-3850 1725) $PN BT67
J 0
(-3840 1735);
DISPLAY 0.489362 (-3840 1735);
PAINT MONO (-3840 1735);
FORCEPROP 0 LASTPIN (-3850 1675) $PN BU66
J 0
(-3840 1685);
DISPLAY 0.489362 (-3840 1685);
PAINT MONO (-3840 1685);
FORCEPROP 0 LASTPIN (-3850 1625) $PN BU67
J 0
(-3840 1635);
DISPLAY 0.489362 (-3840 1635);
PAINT MONO (-3840 1635);
FORCEPROP 0 LASTPIN (-3850 1575) $PN BV65
J 0
(-3840 1585);
DISPLAY 0.489362 (-3840 1585);
PAINT MONO (-3840 1585);
FORCEPROP 0 LASTPIN (-3850 4175) $PN CB67
J 0
(-3840 4185);
DISPLAY 0.489362 (-3840 4185);
PAINT MONO (-3840 4185);
FORCEPROP 0 LASTPIN (-3850 4125) $PN CC66
J 0
(-3840 4135);
DISPLAY 0.489362 (-3840 4135);
PAINT MONO (-3840 4135);
FORCEPROP 0 LASTPIN (-3850 4075) $PN CC67
J 0
(-3840 4085);
DISPLAY 0.489362 (-3840 4085);
PAINT MONO (-3840 4085);
FORCEPROP 0 LASTPIN (-3850 4025) $PN CD65
J 0
(-3840 4035);
DISPLAY 0.489362 (-3840 4035);
PAINT MONO (-3840 4035);
FORCEPROP 0 LASTPIN (-3850 3975) $PN CF67
J 0
(-3840 3985);
DISPLAY 0.489362 (-3840 3985);
PAINT MONO (-3840 3985);
FORCEPROP 0 LASTPIN (-3850 3925) $PN CG66
J 0
(-3840 3935);
DISPLAY 0.489362 (-3840 3935);
PAINT MONO (-3840 3935);
FORCEPROP 0 LASTPIN (-3850 3875) $PN CG67
J 0
(-3840 3885);
DISPLAY 0.489362 (-3840 3885);
PAINT MONO (-3840 3885);
FORCEPROP 0 LASTPIN (-3850 3825) $PN CH65
J 0
(-3840 3835);
DISPLAY 0.489362 (-3840 3835);
PAINT MONO (-3840 3835);
FORCEPROP 0 LASTPIN (-3850 3725) $PN CH67
J 0
(-3840 3735);
DISPLAY 0.489362 (-3840 3735);
PAINT MONO (-3840 3735);
FORCEPROP 0 LASTPIN (-3850 3675) $PN CJ66
J 0
(-3840 3685);
DISPLAY 0.489362 (-3840 3685);
PAINT MONO (-3840 3685);
FORCEPROP 0 LASTPIN (-3850 3625) $PN CJ67
J 0
(-3840 3635);
DISPLAY 0.489362 (-3840 3635);
PAINT MONO (-3840 3635);
FORCEPROP 0 LASTPIN (-3850 3575) $PN CK65
J 0
(-3840 3585);
DISPLAY 0.489362 (-3840 3585);
PAINT MONO (-3840 3585);
FORCEPROP 0 LASTPIN (-3850 3525) $PN CM67
J 0
(-3840 3535);
DISPLAY 0.489362 (-3840 3535);
PAINT MONO (-3840 3535);
FORCEPROP 0 LASTPIN (-3850 3475) $PN CN66
J 0
(-3840 3485);
DISPLAY 0.489362 (-3840 3485);
PAINT MONO (-3840 3485);
FORCEPROP 0 LASTPIN (-3850 3425) $PN CN67
J 0
(-3840 3435);
DISPLAY 0.489362 (-3840 3435);
PAINT MONO (-3840 3435);
FORCEPROP 0 LASTPIN (-3850 3375) $PN CP65
J 0
(-3840 3385);
DISPLAY 0.489362 (-3840 3385);
PAINT MONO (-3840 3385);
FORCEPROP 0 LASTPIN (-3850 3275) $PN CP67
J 0
(-3840 3285);
DISPLAY 0.489362 (-3840 3285);
PAINT MONO (-3840 3285);
FORCEPROP 0 LASTPIN (-3850 3225) $PN CR66
J 0
(-3840 3235);
DISPLAY 0.489362 (-3840 3235);
PAINT MONO (-3840 3235);
FORCEPROP 0 LASTPIN (-3850 3175) $PN CR67
J 0
(-3840 3185);
DISPLAY 0.489362 (-3840 3185);
PAINT MONO (-3840 3185);
FORCEPROP 0 LASTPIN (-3850 3125) $PN CT65
J 0
(-3840 3135);
DISPLAY 0.489362 (-3840 3135);
PAINT MONO (-3840 3135);
FORCEPROP 0 LASTPIN (-3850 3075) $PN CV67
J 0
(-3840 3085);
DISPLAY 0.489362 (-3840 3085);
PAINT MONO (-3840 3085);
FORCEPROP 0 LASTPIN (-3850 3025) $PN CW66
J 0
(-3840 3035);
DISPLAY 0.489362 (-3840 3035);
PAINT MONO (-3840 3035);
FORCEPROP 0 LASTPIN (-3850 2975) $PN CW67
J 0
(-3840 2985);
DISPLAY 0.489362 (-3840 2985);
PAINT MONO (-3840 2985);
FORCEPROP 0 LASTPIN (-3850 2925) $PN CY65
J 0
(-3840 2935);
DISPLAY 0.489362 (-3840 2935);
PAINT MONO (-3840 2935);
FORCEPROP 0 LASTPIN (-3850 2825) $PN CY67
J 0
(-3840 2835);
DISPLAY 0.489362 (-3840 2835);
PAINT MONO (-3840 2835);
FORCEPROP 0 LASTPIN (-3850 2775) $PN DA66
J 0
(-3840 2785);
DISPLAY 0.489362 (-3840 2785);
PAINT MONO (-3840 2785);
FORCEPROP 0 LASTPIN (-3850 2725) $PN DA67
J 0
(-3840 2735);
DISPLAY 0.489362 (-3840 2735);
PAINT MONO (-3840 2735);
FORCEPROP 0 LASTPIN (-3850 2675) $PN DB65
J 0
(-3840 2685);
DISPLAY 0.489362 (-3840 2685);
PAINT MONO (-3840 2685);
FORCEPROP 0 LASTPIN (-3850 2625) $PN DD67
J 0
(-3840 2635);
DISPLAY 0.489362 (-3840 2635);
PAINT MONO (-3840 2635);
FORCEPROP 0 LASTPIN (-3850 2575) $PN DE66
J 0
(-3840 2585);
DISPLAY 0.489362 (-3840 2585);
PAINT MONO (-3840 2585);
FORCEPROP 0 LASTPIN (-3850 2525) $PN DE67
J 0
(-3840 2535);
DISPLAY 0.489362 (-3840 2535);
PAINT MONO (-3840 2535);
FORCEPROP 0 LASTPIN (-3850 2475) $PN DF67
J 0
(-3840 2485);
DISPLAY 0.489362 (-3840 2485);
PAINT MONO (-3840 2485);
FORCEPROP 0 LASTPIN (-5450 4925) $PN CD67
J 2
(-5460 4935);
DISPLAY 0.489362 (-5460 4935);
PAINT MONO (-5460 4935);
FORCEPROP 0 LASTPIN (-5450 4825) $PN CK67
J 2
(-5460 4835);
DISPLAY 0.489362 (-5460 4835);
PAINT MONO (-5460 4835);
FORCEPROP 0 LASTPIN (-5450 4725) $PN CT67
J 2
(-5460 4735);
DISPLAY 0.489362 (-5460 4735);
PAINT MONO (-5460 4735);
FORCEPROP 0 LASTPIN (-5450 4625) $PN DB67
J 2
(-5460 4635);
DISPLAY 0.489362 (-5460 4635);
PAINT MONO (-5460 4635);
FORCEPROP 0 LASTPIN (-5450 4525) $PN BY65
J 2
(-5460 4535);
DISPLAY 0.489362 (-5460 4535);
PAINT MONO (-5460 4535);
FORCEPROP 0 LASTPIN (-5450 4425) $PN CF65
J 2
(-5460 4435);
DISPLAY 0.489362 (-5460 4435);
PAINT MONO (-5460 4435);
FORCEPROP 0 LASTPIN (-5450 4325) $PN CM65
J 2
(-5460 4335);
DISPLAY 0.489362 (-5460 4335);
PAINT MONO (-5460 4335);
FORCEPROP 0 LASTPIN (-5450 4225) $PN CV65
J 2
(-5460 4235);
DISPLAY 0.489362 (-5460 4235);
PAINT MONO (-5460 4235);
FORCEPROP 0 LASTPIN (-5450 4125) $PN DD65
J 2
(-5460 4135);
DISPLAY 0.489362 (-5460 4135);
PAINT MONO (-5460 4135);
FORCEPROP 0 LASTPIN (-5450 4025) $PN BV67
J 2
(-5460 4035);
DISPLAY 0.489362 (-5460 4035);
PAINT MONO (-5460 4035);
FORCEPROP 0 LASTPIN (-5450 4875) $PN CE67
J 2
(-5460 4885);
DISPLAY 0.489362 (-5460 4885);
PAINT MONO (-5460 4885);
FORCEPROP 0 LASTPIN (-5450 4775) $PN CL67
J 2
(-5460 4785);
DISPLAY 0.489362 (-5460 4785);
PAINT MONO (-5460 4785);
FORCEPROP 0 LASTPIN (-5450 4675) $PN CU67
J 2
(-5460 4685);
DISPLAY 0.489362 (-5460 4685);
PAINT MONO (-5460 4685);
FORCEPROP 0 LASTPIN (-5450 4575) $PN DC67
J 2
(-5460 4585);
DISPLAY 0.489362 (-5460 4585);
PAINT MONO (-5460 4585);
FORCEPROP 0 LASTPIN (-5450 4475) $PN BW66
J 2
(-5460 4485);
DISPLAY 0.489362 (-5460 4485);
PAINT MONO (-5460 4485);
FORCEPROP 0 LASTPIN (-5450 4375) $PN CE66
J 2
(-5460 4385);
DISPLAY 0.489362 (-5460 4385);
PAINT MONO (-5460 4385);
FORCEPROP 0 LASTPIN (-5450 4275) $PN CL66
J 2
(-5460 4285);
DISPLAY 0.489362 (-5460 4285);
PAINT MONO (-5460 4285);
FORCEPROP 0 LASTPIN (-5450 4175) $PN CU66
J 2
(-5460 4185);
DISPLAY 0.489362 (-5460 4185);
PAINT MONO (-5460 4185);
FORCEPROP 0 LASTPIN (-5450 4075) $PN DC66
J 2
(-5460 4085);
DISPLAY 0.489362 (-5460 4085);
PAINT MONO (-5460 4085);
FORCEPROP 0 LASTPIN (-5450 3975) $PN BW67
J 2
(-5460 3985);
DISPLAY 0.489362 (-5460 3985);
PAINT MONO (-5460 3985);
FORCEPROP 0 LASTPIN (-5450 2225) $PN BL67
J 2
(-5460 2235);
DISPLAY 0.489362 (-5460 2235);
PAINT MONO (-5460 2235);
FORCEPROP 0 LASTPIN (-5450 1175) $PN BF65
J 2
(-5460 1185);
DISPLAY 0.489362 (-5460 1185);
PAINT MONO (-5460 1185);
FORCEPROP 2 LAST PART_TYPE SMLF
J 0
(-5300 6350);
DISPLAY 1.021277 (-5300 6350);
FORCEPROP 1 LAST MATERIAL IO
J 0
(-5295 6157);
DISPLAY 0.489362 (-5295 6157);
PAINT SKYBLUE (-5295 6157);
FORCEPROP 2 LAST VALUE SOCKET6096_13568-001
J 0
(-5300 6250);
DISPLAY 0.489362 (-5300 6250);
PAINT SKYBLUE (-5300 6250);
FORCEPROP 1 LAST PART_NUMBER DGA^6000030
J 0
(-5295 6284);
DISPLAY 0.489362 (-5295 6284);
PAINT SKYBLUE (-5295 6284);
FORCEPROP 2 LAST CDS_LIB pure_quanta
J 0
(-4650 3600);
DISPLAY INVISIBLE (-4650 3600);
FORCEPROP 1 LAST CDS_LMAN_SYM_OUTLINE -650,2525,650,-2525
J 0
(-4650 3600);
DISPLAY 0.468085 (-4650 3600);
PAINT GREEN (-4650 3600);
DISPLAY INVISIBLE (-4650 3600);
FORCEPROP 1 LAST NEEDS_NO_SIZE TRUE
J 0
(-4650 3600);
DISPLAY 0.723404 (-4650 3600);
PAINT GREEN (-4650 3600);
DISPLAY INVISIBLE (-4650 3600);
FORCEPROP 1 LAST PATH I159
J 0
(-4650 3600);
DISPLAY 0.723404 (-4650 3600);
PAINT GREEN (-4650 3600);
DISPLAY INVISIBLE (-4650 3600);
FORCEADD OFFPAGE..3
(-2650 6000);
FORCEPROP 2 LAST $XR0 90 
J 0
(-2436 6000);
DISPLAY 0.638298 (-2436 6000);
PAINT MONO (-2436 6000);
FORCEPROP 2 LAST PATH I160
J 0
(-2425 6050);
DISPLAY 1.021277 (-2425 6050);
DISPLAY INVISIBLE (-2425 6050);
FORCEPROP 1 LAST COMMENT_BODY TRUE
J 0
(-2700 5900);
DISPLAY 0.872340 (-2700 5900);
PAINT GREEN (-2700 5900);
DISPLAY INVISIBLE (-2700 5900);
FORCEPROP 1 LAST OFFPAGE TRUE
J 0
(-2325 5875);
DISPLAY 0.872340 (-2325 5875);
PAINT GREEN (-2325 5875);
DISPLAY INVISIBLE (-2325 5875);
FORCEPROP 2 LAST CDS_LIB mstr_standard
J 0
(-2650 6000);
DISPLAY 0.723404 (-2650 6000);
PAINT MONO (-2650 6000);
DISPLAY INVISIBLE (-2650 6000);
FORCEADD OFFPAGE..3
(-2650 4200);
FORCEPROP 2 LAST $XR0 90 
J 0
(-2436 4200);
DISPLAY 0.638298 (-2436 4200);
PAINT MONO (-2436 4200);
FORCEPROP 2 LAST PATH I161
J 0
(-2425 4250);
DISPLAY 1.021277 (-2425 4250);
DISPLAY INVISIBLE (-2425 4250);
FORCEPROP 1 LAST COMMENT_BODY TRUE
J 0
(-2700 4100);
DISPLAY 0.872340 (-2700 4100);
PAINT GREEN (-2700 4100);
DISPLAY INVISIBLE (-2700 4100);
FORCEPROP 1 LAST OFFPAGE TRUE
J 0
(-2325 4075);
DISPLAY 0.872340 (-2325 4075);
PAINT GREEN (-2325 4075);
DISPLAY INVISIBLE (-2325 4075);
FORCEPROP 2 LAST CDS_LIB mstr_standard
J 0
(-2650 4200);
DISPLAY 0.723404 (-2650 4200);
PAINT MONO (-2650 4200);
DISPLAY INVISIBLE (-2650 4200);
FORCEADD TAP..1
(-3375 5975);
FORCEPROP 3 LASTPIN (-3425 5975) SIG_NAME M_F_CPU0_SA_DQ<0>
J 0
(-3415 5985);
DISPLAY 0.659574 (-3415 5985);
PAINT MONO (-3415 5985);
DISPLAY INVISIBLE (-3415 5985);
FORCEPROP 1 LASTPIN (-3425 5975) BN 0
J 0
(-3437 5983);
DISPLAY 0.489362 (-3437 5983);
PAINT GREEN (-3437 5983);
FORCEPROP 2 LAST CDS_LIB mstr_standard
J 0
(-3375 5975);
DISPLAY 0.723404 (-3375 5975);
PAINT MONO (-3375 5975);
DISPLAY INVISIBLE (-3375 5975);
FORCEPROP 1 LAST BODY_TYPE PLUMBING
J 0
(-3375 6025);
DISPLAY 0.872340 (-3375 6025);
PAINT GREEN (-3375 6025);
DISPLAY INVISIBLE (-3375 6025);
FORCEPROP 1 LAST HDL_TAP TRUE
J 0
(-3050 5850);
DISPLAY 0.872340 (-3050 5850);
DISPLAY INVISIBLE (-3050 5850);
FORCEPROP 1 LAST PATH I162
J 0
(-3377 5975);
DISPLAY 0.872340 (-3377 5975);
PAINT GREEN (-3377 5975);
DISPLAY INVISIBLE (-3377 5975);
FORCEADD TAP..1
(-3375 5925);
FORCEPROP 3 LASTPIN (-3425 5925) SIG_NAME M_F_CPU0_SA_DQ<1>
J 0
(-3415 5935);
DISPLAY 0.659574 (-3415 5935);
PAINT MONO (-3415 5935);
DISPLAY INVISIBLE (-3415 5935);
FORCEPROP 1 LASTPIN (-3425 5925) BN 1
J 0
(-3437 5933);
DISPLAY 0.489362 (-3437 5933);
PAINT GREEN (-3437 5933);
FORCEPROP 2 LAST CDS_LIB mstr_standard
J 0
(-3375 5925);
DISPLAY 0.723404 (-3375 5925);
PAINT MONO (-3375 5925);
DISPLAY INVISIBLE (-3375 5925);
FORCEPROP 1 LAST BODY_TYPE PLUMBING
J 0
(-3375 5975);
DISPLAY 0.872340 (-3375 5975);
PAINT GREEN (-3375 5975);
DISPLAY INVISIBLE (-3375 5975);
FORCEPROP 1 LAST HDL_TAP TRUE
J 0
(-3050 5800);
DISPLAY 0.872340 (-3050 5800);
DISPLAY INVISIBLE (-3050 5800);
FORCEPROP 1 LAST PATH I163
J 0
(-3377 5925);
DISPLAY 0.872340 (-3377 5925);
PAINT GREEN (-3377 5925);
DISPLAY INVISIBLE (-3377 5925);
FORCEADD TAP..1
(-3375 5775);
FORCEPROP 3 LASTPIN (-3425 5775) SIG_NAME M_F_CPU0_SA_DQ<4>
J 0
(-3415 5785);
DISPLAY 0.659574 (-3415 5785);
PAINT MONO (-3415 5785);
DISPLAY INVISIBLE (-3415 5785);
FORCEPROP 1 LASTPIN (-3425 5775) BN 4
J 0
(-3437 5783);
DISPLAY 0.489362 (-3437 5783);
PAINT GREEN (-3437 5783);
FORCEPROP 2 LAST CDS_LIB mstr_standard
J 0
(-3375 5775);
DISPLAY 0.723404 (-3375 5775);
PAINT MONO (-3375 5775);
DISPLAY INVISIBLE (-3375 5775);
FORCEPROP 1 LAST BODY_TYPE PLUMBING
J 0
(-3375 5825);
DISPLAY 0.872340 (-3375 5825);
PAINT GREEN (-3375 5825);
DISPLAY INVISIBLE (-3375 5825);
FORCEPROP 1 LAST HDL_TAP TRUE
J 0
(-3050 5650);
DISPLAY 0.872340 (-3050 5650);
DISPLAY INVISIBLE (-3050 5650);
FORCEPROP 1 LAST PATH I164
J 0
(-3377 5775);
DISPLAY 0.872340 (-3377 5775);
PAINT GREEN (-3377 5775);
DISPLAY INVISIBLE (-3377 5775);
FORCEADD TAP..1
(-3375 5825);
FORCEPROP 3 LASTPIN (-3425 5825) SIG_NAME M_F_CPU0_SA_DQ<3>
J 0
(-3415 5835);
DISPLAY 0.659574 (-3415 5835);
PAINT MONO (-3415 5835);
DISPLAY INVISIBLE (-3415 5835);
FORCEPROP 1 LASTPIN (-3425 5825) BN 3
J 0
(-3437 5833);
DISPLAY 0.489362 (-3437 5833);
PAINT GREEN (-3437 5833);
FORCEPROP 2 LAST CDS_LIB mstr_standard
J 0
(-3375 5825);
DISPLAY 0.723404 (-3375 5825);
PAINT MONO (-3375 5825);
DISPLAY INVISIBLE (-3375 5825);
FORCEPROP 1 LAST BODY_TYPE PLUMBING
J 0
(-3375 5875);
DISPLAY 0.872340 (-3375 5875);
PAINT GREEN (-3375 5875);
DISPLAY INVISIBLE (-3375 5875);
FORCEPROP 1 LAST HDL_TAP TRUE
J 0
(-3050 5700);
DISPLAY 0.872340 (-3050 5700);
DISPLAY INVISIBLE (-3050 5700);
FORCEPROP 1 LAST PATH I165
J 0
(-3377 5825);
DISPLAY 0.872340 (-3377 5825);
PAINT GREEN (-3377 5825);
DISPLAY INVISIBLE (-3377 5825);
FORCEADD TAP..1
(-3375 5875);
FORCEPROP 3 LASTPIN (-3425 5875) SIG_NAME M_F_CPU0_SA_DQ<2>
J 0
(-3415 5885);
DISPLAY 0.659574 (-3415 5885);
PAINT MONO (-3415 5885);
DISPLAY INVISIBLE (-3415 5885);
FORCEPROP 1 LASTPIN (-3425 5875) BN 2
J 0
(-3437 5883);
DISPLAY 0.489362 (-3437 5883);
PAINT GREEN (-3437 5883);
FORCEPROP 2 LAST CDS_LIB mstr_standard
J 0
(-3375 5875);
DISPLAY 0.723404 (-3375 5875);
PAINT MONO (-3375 5875);
DISPLAY INVISIBLE (-3375 5875);
FORCEPROP 1 LAST BODY_TYPE PLUMBING
J 0
(-3375 5925);
DISPLAY 0.872340 (-3375 5925);
PAINT GREEN (-3375 5925);
DISPLAY INVISIBLE (-3375 5925);
FORCEPROP 1 LAST HDL_TAP TRUE
J 0
(-3050 5750);
DISPLAY 0.872340 (-3050 5750);
DISPLAY INVISIBLE (-3050 5750);
FORCEPROP 1 LAST PATH I166
J 0
(-3377 5875);
DISPLAY 0.872340 (-3377 5875);
PAINT GREEN (-3377 5875);
DISPLAY INVISIBLE (-3377 5875);
FORCEADD TAP..1
(-3375 5675);
FORCEPROP 3 LASTPIN (-3425 5675) SIG_NAME M_F_CPU0_SA_DQ<6>
J 0
(-3415 5685);
DISPLAY 0.659574 (-3415 5685);
PAINT MONO (-3415 5685);
DISPLAY INVISIBLE (-3415 5685);
FORCEPROP 1 LASTPIN (-3425 5675) BN 6
J 0
(-3437 5683);
DISPLAY 0.489362 (-3437 5683);
PAINT GREEN (-3437 5683);
FORCEPROP 2 LAST CDS_LIB mstr_standard
J 0
(-3375 5675);
DISPLAY 0.723404 (-3375 5675);
PAINT MONO (-3375 5675);
DISPLAY INVISIBLE (-3375 5675);
FORCEPROP 1 LAST BODY_TYPE PLUMBING
J 0
(-3375 5725);
DISPLAY 0.872340 (-3375 5725);
PAINT GREEN (-3375 5725);
DISPLAY INVISIBLE (-3375 5725);
FORCEPROP 1 LAST HDL_TAP TRUE
J 0
(-3050 5550);
DISPLAY 0.872340 (-3050 5550);
DISPLAY INVISIBLE (-3050 5550);
FORCEPROP 1 LAST PATH I167
J 0
(-3377 5675);
DISPLAY 0.872340 (-3377 5675);
PAINT GREEN (-3377 5675);
DISPLAY INVISIBLE (-3377 5675);
FORCEADD TAP..1
(-3375 5725);
FORCEPROP 3 LASTPIN (-3425 5725) SIG_NAME M_F_CPU0_SA_DQ<5>
J 0
(-3415 5735);
DISPLAY 0.659574 (-3415 5735);
PAINT MONO (-3415 5735);
DISPLAY INVISIBLE (-3415 5735);
FORCEPROP 1 LASTPIN (-3425 5725) BN 5
J 0
(-3437 5733);
DISPLAY 0.489362 (-3437 5733);
PAINT GREEN (-3437 5733);
FORCEPROP 2 LAST CDS_LIB mstr_standard
J 0
(-3375 5725);
DISPLAY 0.723404 (-3375 5725);
PAINT MONO (-3375 5725);
DISPLAY INVISIBLE (-3375 5725);
FORCEPROP 1 LAST BODY_TYPE PLUMBING
J 0
(-3375 5775);
DISPLAY 0.872340 (-3375 5775);
PAINT GREEN (-3375 5775);
DISPLAY INVISIBLE (-3375 5775);
FORCEPROP 1 LAST HDL_TAP TRUE
J 0
(-3050 5600);
DISPLAY 0.872340 (-3050 5600);
DISPLAY INVISIBLE (-3050 5600);
FORCEPROP 1 LAST PATH I168
J 0
(-3377 5725);
DISPLAY 0.872340 (-3377 5725);
PAINT GREEN (-3377 5725);
DISPLAY INVISIBLE (-3377 5725);
FORCEADD TAP..1
(-3375 5525);
FORCEPROP 3 LASTPIN (-3425 5525) SIG_NAME M_F_CPU0_SA_DQ<8>
J 0
(-3415 5535);
DISPLAY 0.659574 (-3415 5535);
PAINT MONO (-3415 5535);
DISPLAY INVISIBLE (-3415 5535);
FORCEPROP 1 LASTPIN (-3425 5525) BN 8
J 0
(-3437 5533);
DISPLAY 0.489362 (-3437 5533);
PAINT GREEN (-3437 5533);
FORCEPROP 2 LAST CDS_LIB mstr_standard
J 0
(-3375 5525);
DISPLAY 0.723404 (-3375 5525);
PAINT MONO (-3375 5525);
DISPLAY INVISIBLE (-3375 5525);
FORCEPROP 1 LAST BODY_TYPE PLUMBING
J 0
(-3375 5575);
DISPLAY 0.872340 (-3375 5575);
PAINT GREEN (-3375 5575);
DISPLAY INVISIBLE (-3375 5575);
FORCEPROP 1 LAST HDL_TAP TRUE
J 0
(-3050 5400);
DISPLAY 0.872340 (-3050 5400);
DISPLAY INVISIBLE (-3050 5400);
FORCEPROP 1 LAST PATH I169
J 0
(-3377 5525);
DISPLAY 0.872340 (-3377 5525);
PAINT GREEN (-3377 5525);
DISPLAY INVISIBLE (-3377 5525);
FORCEADD TAP..1
(-3375 5625);
FORCEPROP 3 LASTPIN (-3425 5625) SIG_NAME M_F_CPU0_SA_DQ<7>
J 0
(-3415 5635);
DISPLAY 0.659574 (-3415 5635);
PAINT MONO (-3415 5635);
DISPLAY INVISIBLE (-3415 5635);
FORCEPROP 1 LASTPIN (-3425 5625) BN 7
J 0
(-3437 5633);
DISPLAY 0.489362 (-3437 5633);
PAINT GREEN (-3437 5633);
FORCEPROP 2 LAST CDS_LIB mstr_standard
J 0
(-3375 5625);
DISPLAY 0.723404 (-3375 5625);
PAINT MONO (-3375 5625);
DISPLAY INVISIBLE (-3375 5625);
FORCEPROP 1 LAST BODY_TYPE PLUMBING
J 0
(-3375 5675);
DISPLAY 0.872340 (-3375 5675);
PAINT GREEN (-3375 5675);
DISPLAY INVISIBLE (-3375 5675);
FORCEPROP 1 LAST HDL_TAP TRUE
J 0
(-3050 5500);
DISPLAY 0.872340 (-3050 5500);
DISPLAY INVISIBLE (-3050 5500);
FORCEPROP 1 LAST PATH I170
J 0
(-3377 5625);
DISPLAY 0.872340 (-3377 5625);
PAINT GREEN (-3377 5625);
DISPLAY INVISIBLE (-3377 5625);
FORCEADD TAP..1
(-3375 5475);
FORCEPROP 3 LASTPIN (-3425 5475) SIG_NAME M_F_CPU0_SA_DQ<9>
J 0
(-3415 5485);
DISPLAY 0.659574 (-3415 5485);
PAINT MONO (-3415 5485);
DISPLAY INVISIBLE (-3415 5485);
FORCEPROP 1 LASTPIN (-3425 5475) BN 9
J 0
(-3437 5483);
DISPLAY 0.489362 (-3437 5483);
PAINT GREEN (-3437 5483);
FORCEPROP 2 LAST CDS_LIB mstr_standard
J 0
(-3375 5475);
DISPLAY 0.723404 (-3375 5475);
PAINT MONO (-3375 5475);
DISPLAY INVISIBLE (-3375 5475);
FORCEPROP 1 LAST BODY_TYPE PLUMBING
J 0
(-3375 5525);
DISPLAY 0.872340 (-3375 5525);
PAINT GREEN (-3375 5525);
DISPLAY INVISIBLE (-3375 5525);
FORCEPROP 1 LAST HDL_TAP TRUE
J 0
(-3050 5350);
DISPLAY 0.872340 (-3050 5350);
DISPLAY INVISIBLE (-3050 5350);
FORCEPROP 1 LAST PATH I171
J 0
(-3377 5475);
DISPLAY 0.872340 (-3377 5475);
PAINT GREEN (-3377 5475);
DISPLAY INVISIBLE (-3377 5475);
FORCEADD TAP..1
(-3375 5425);
FORCEPROP 3 LASTPIN (-3425 5425) SIG_NAME M_F_CPU0_SA_DQ<10>
J 0
(-3415 5435);
DISPLAY 0.659574 (-3415 5435);
PAINT MONO (-3415 5435);
DISPLAY INVISIBLE (-3415 5435);
FORCEPROP 1 LASTPIN (-3425 5425) BN 10
J 0
(-3437 5433);
DISPLAY 0.489362 (-3437 5433);
PAINT GREEN (-3437 5433);
FORCEPROP 2 LAST CDS_LIB mstr_standard
J 0
(-3375 5425);
DISPLAY 0.723404 (-3375 5425);
PAINT MONO (-3375 5425);
DISPLAY INVISIBLE (-3375 5425);
FORCEPROP 1 LAST BODY_TYPE PLUMBING
J 0
(-3375 5475);
DISPLAY 0.872340 (-3375 5475);
PAINT GREEN (-3375 5475);
DISPLAY INVISIBLE (-3375 5475);
FORCEPROP 1 LAST HDL_TAP TRUE
J 0
(-3050 5300);
DISPLAY 0.872340 (-3050 5300);
DISPLAY INVISIBLE (-3050 5300);
FORCEPROP 1 LAST PATH I172
J 0
(-3377 5425);
DISPLAY 0.872340 (-3377 5425);
PAINT GREEN (-3377 5425);
DISPLAY INVISIBLE (-3377 5425);
FORCEADD TAP..1
(-3375 5275);
FORCEPROP 3 LASTPIN (-3425 5275) SIG_NAME M_F_CPU0_SA_DQ<13>
J 0
(-3415 5285);
DISPLAY 0.659574 (-3415 5285);
PAINT MONO (-3415 5285);
DISPLAY INVISIBLE (-3415 5285);
FORCEPROP 1 LASTPIN (-3425 5275) BN 13
J 0
(-3437 5283);
DISPLAY 0.489362 (-3437 5283);
PAINT GREEN (-3437 5283);
FORCEPROP 2 LAST CDS_LIB mstr_standard
J 0
(-3375 5275);
DISPLAY 0.723404 (-3375 5275);
PAINT MONO (-3375 5275);
DISPLAY INVISIBLE (-3375 5275);
FORCEPROP 1 LAST BODY_TYPE PLUMBING
J 0
(-3375 5325);
DISPLAY 0.872340 (-3375 5325);
PAINT GREEN (-3375 5325);
DISPLAY INVISIBLE (-3375 5325);
FORCEPROP 1 LAST HDL_TAP TRUE
J 0
(-3050 5150);
DISPLAY 0.872340 (-3050 5150);
DISPLAY INVISIBLE (-3050 5150);
FORCEPROP 1 LAST PATH I173
J 0
(-3377 5275);
DISPLAY 0.872340 (-3377 5275);
PAINT GREEN (-3377 5275);
DISPLAY INVISIBLE (-3377 5275);
FORCEADD TAP..1
(-3375 5325);
FORCEPROP 3 LASTPIN (-3425 5325) SIG_NAME M_F_CPU0_SA_DQ<12>
J 0
(-3415 5335);
DISPLAY 0.659574 (-3415 5335);
PAINT MONO (-3415 5335);
DISPLAY INVISIBLE (-3415 5335);
FORCEPROP 1 LASTPIN (-3425 5325) BN 12
J 0
(-3437 5333);
DISPLAY 0.489362 (-3437 5333);
PAINT GREEN (-3437 5333);
FORCEPROP 2 LAST CDS_LIB mstr_standard
J 0
(-3375 5325);
DISPLAY 0.723404 (-3375 5325);
PAINT MONO (-3375 5325);
DISPLAY INVISIBLE (-3375 5325);
FORCEPROP 1 LAST BODY_TYPE PLUMBING
J 0
(-3375 5375);
DISPLAY 0.872340 (-3375 5375);
PAINT GREEN (-3375 5375);
DISPLAY INVISIBLE (-3375 5375);
FORCEPROP 1 LAST HDL_TAP TRUE
J 0
(-3050 5200);
DISPLAY 0.872340 (-3050 5200);
DISPLAY INVISIBLE (-3050 5200);
FORCEPROP 1 LAST PATH I174
J 0
(-3377 5325);
DISPLAY 0.872340 (-3377 5325);
PAINT GREEN (-3377 5325);
DISPLAY INVISIBLE (-3377 5325);
FORCEADD TAP..1
(-3375 5375);
FORCEPROP 3 LASTPIN (-3425 5375) SIG_NAME M_F_CPU0_SA_DQ<11>
J 0
(-3415 5385);
DISPLAY 0.659574 (-3415 5385);
PAINT MONO (-3415 5385);
DISPLAY INVISIBLE (-3415 5385);
FORCEPROP 1 LASTPIN (-3425 5375) BN 11
J 0
(-3437 5383);
DISPLAY 0.489362 (-3437 5383);
PAINT GREEN (-3437 5383);
FORCEPROP 2 LAST CDS_LIB mstr_standard
J 0
(-3375 5375);
DISPLAY 0.723404 (-3375 5375);
PAINT MONO (-3375 5375);
DISPLAY INVISIBLE (-3375 5375);
FORCEPROP 1 LAST BODY_TYPE PLUMBING
J 0
(-3375 5425);
DISPLAY 0.872340 (-3375 5425);
PAINT GREEN (-3375 5425);
DISPLAY INVISIBLE (-3375 5425);
FORCEPROP 1 LAST HDL_TAP TRUE
J 0
(-3050 5250);
DISPLAY 0.872340 (-3050 5250);
DISPLAY INVISIBLE (-3050 5250);
FORCEPROP 1 LAST PATH I175
J 0
(-3377 5375);
DISPLAY 0.872340 (-3377 5375);
PAINT GREEN (-3377 5375);
DISPLAY INVISIBLE (-3377 5375);
FORCEADD TAP..1
(-3375 5175);
FORCEPROP 3 LASTPIN (-3425 5175) SIG_NAME M_F_CPU0_SA_DQ<15>
J 0
(-3415 5185);
DISPLAY 0.659574 (-3415 5185);
PAINT MONO (-3415 5185);
DISPLAY INVISIBLE (-3415 5185);
FORCEPROP 1 LASTPIN (-3425 5175) BN 15
J 0
(-3437 5183);
DISPLAY 0.489362 (-3437 5183);
PAINT GREEN (-3437 5183);
FORCEPROP 2 LAST CDS_LIB mstr_standard
J 0
(-3375 5175);
DISPLAY 0.723404 (-3375 5175);
PAINT MONO (-3375 5175);
DISPLAY INVISIBLE (-3375 5175);
FORCEPROP 1 LAST BODY_TYPE PLUMBING
J 0
(-3375 5225);
DISPLAY 0.872340 (-3375 5225);
PAINT GREEN (-3375 5225);
DISPLAY INVISIBLE (-3375 5225);
FORCEPROP 1 LAST HDL_TAP TRUE
J 0
(-3050 5050);
DISPLAY 0.872340 (-3050 5050);
DISPLAY INVISIBLE (-3050 5050);
FORCEPROP 1 LAST PATH I176
J 0
(-3377 5175);
DISPLAY 0.872340 (-3377 5175);
PAINT GREEN (-3377 5175);
DISPLAY INVISIBLE (-3377 5175);
FORCEADD TAP..1
(-3375 5225);
FORCEPROP 3 LASTPIN (-3425 5225) SIG_NAME M_F_CPU0_SA_DQ<14>
J 0
(-3415 5235);
DISPLAY 0.659574 (-3415 5235);
PAINT MONO (-3415 5235);
DISPLAY INVISIBLE (-3415 5235);
FORCEPROP 1 LASTPIN (-3425 5225) BN 14
J 0
(-3437 5233);
DISPLAY 0.489362 (-3437 5233);
PAINT GREEN (-3437 5233);
FORCEPROP 2 LAST CDS_LIB mstr_standard
J 0
(-3375 5225);
DISPLAY 0.723404 (-3375 5225);
PAINT MONO (-3375 5225);
DISPLAY INVISIBLE (-3375 5225);
FORCEPROP 1 LAST BODY_TYPE PLUMBING
J 0
(-3375 5275);
DISPLAY 0.872340 (-3375 5275);
PAINT GREEN (-3375 5275);
DISPLAY INVISIBLE (-3375 5275);
FORCEPROP 1 LAST HDL_TAP TRUE
J 0
(-3050 5100);
DISPLAY 0.872340 (-3050 5100);
DISPLAY INVISIBLE (-3050 5100);
FORCEPROP 1 LAST PATH I177
J 0
(-3377 5225);
DISPLAY 0.872340 (-3377 5225);
PAINT GREEN (-3377 5225);
DISPLAY INVISIBLE (-3377 5225);
FORCEADD TAP..1
(-3375 5025);
FORCEPROP 3 LASTPIN (-3425 5025) SIG_NAME M_F_CPU0_SA_DQ<17>
J 0
(-3415 5035);
DISPLAY 0.659574 (-3415 5035);
PAINT MONO (-3415 5035);
DISPLAY INVISIBLE (-3415 5035);
FORCEPROP 1 LASTPIN (-3425 5025) BN 17
J 0
(-3437 5033);
DISPLAY 0.489362 (-3437 5033);
PAINT GREEN (-3437 5033);
FORCEPROP 2 LAST CDS_LIB mstr_standard
J 0
(-3375 5025);
DISPLAY 0.723404 (-3375 5025);
PAINT MONO (-3375 5025);
DISPLAY INVISIBLE (-3375 5025);
FORCEPROP 1 LAST BODY_TYPE PLUMBING
J 0
(-3375 5075);
DISPLAY 0.872340 (-3375 5075);
PAINT GREEN (-3375 5075);
DISPLAY INVISIBLE (-3375 5075);
FORCEPROP 1 LAST HDL_TAP TRUE
J 0
(-3050 4900);
DISPLAY 0.872340 (-3050 4900);
DISPLAY INVISIBLE (-3050 4900);
FORCEPROP 1 LAST PATH I178
J 0
(-3377 5025);
DISPLAY 0.872340 (-3377 5025);
PAINT GREEN (-3377 5025);
DISPLAY INVISIBLE (-3377 5025);
FORCEADD TAP..1
(-3375 5075);
FORCEPROP 3 LASTPIN (-3425 5075) SIG_NAME M_F_CPU0_SA_DQ<16>
J 0
(-3415 5085);
DISPLAY 0.659574 (-3415 5085);
PAINT MONO (-3415 5085);
DISPLAY INVISIBLE (-3415 5085);
FORCEPROP 1 LASTPIN (-3425 5075) BN 16
J 0
(-3437 5083);
DISPLAY 0.489362 (-3437 5083);
PAINT GREEN (-3437 5083);
FORCEPROP 2 LAST CDS_LIB mstr_standard
J 0
(-3375 5075);
DISPLAY 0.723404 (-3375 5075);
PAINT MONO (-3375 5075);
DISPLAY INVISIBLE (-3375 5075);
FORCEPROP 1 LAST BODY_TYPE PLUMBING
J 0
(-3375 5125);
DISPLAY 0.872340 (-3375 5125);
PAINT GREEN (-3375 5125);
DISPLAY INVISIBLE (-3375 5125);
FORCEPROP 1 LAST HDL_TAP TRUE
J 0
(-3050 4950);
DISPLAY 0.872340 (-3050 4950);
DISPLAY INVISIBLE (-3050 4950);
FORCEPROP 1 LAST PATH I179
J 0
(-3377 5075);
DISPLAY 0.872340 (-3377 5075);
PAINT GREEN (-3377 5075);
DISPLAY INVISIBLE (-3377 5075);
FORCEADD TAP..1
(-3375 4875);
FORCEPROP 3 LASTPIN (-3425 4875) SIG_NAME M_F_CPU0_SA_DQ<20>
J 0
(-3415 4885);
DISPLAY 0.659574 (-3415 4885);
PAINT MONO (-3415 4885);
DISPLAY INVISIBLE (-3415 4885);
FORCEPROP 1 LASTPIN (-3425 4875) BN 20
J 0
(-3437 4883);
DISPLAY 0.489362 (-3437 4883);
PAINT GREEN (-3437 4883);
FORCEPROP 2 LAST CDS_LIB mstr_standard
J 0
(-3375 4875);
DISPLAY 0.723404 (-3375 4875);
PAINT MONO (-3375 4875);
DISPLAY INVISIBLE (-3375 4875);
FORCEPROP 1 LAST BODY_TYPE PLUMBING
J 0
(-3375 4925);
DISPLAY 0.872340 (-3375 4925);
PAINT GREEN (-3375 4925);
DISPLAY INVISIBLE (-3375 4925);
FORCEPROP 1 LAST HDL_TAP TRUE
J 0
(-3050 4750);
DISPLAY 0.872340 (-3050 4750);
DISPLAY INVISIBLE (-3050 4750);
FORCEPROP 1 LAST PATH I180
J 0
(-3377 4875);
DISPLAY 0.872340 (-3377 4875);
PAINT GREEN (-3377 4875);
DISPLAY INVISIBLE (-3377 4875);
FORCEADD TAP..1
(-3375 4925);
FORCEPROP 3 LASTPIN (-3425 4925) SIG_NAME M_F_CPU0_SA_DQ<19>
J 0
(-3415 4935);
DISPLAY 0.659574 (-3415 4935);
PAINT MONO (-3415 4935);
DISPLAY INVISIBLE (-3415 4935);
FORCEPROP 1 LASTPIN (-3425 4925) BN 19
J 0
(-3437 4933);
DISPLAY 0.489362 (-3437 4933);
PAINT GREEN (-3437 4933);
FORCEPROP 2 LAST CDS_LIB mstr_standard
J 0
(-3375 4925);
DISPLAY 0.723404 (-3375 4925);
PAINT MONO (-3375 4925);
DISPLAY INVISIBLE (-3375 4925);
FORCEPROP 1 LAST BODY_TYPE PLUMBING
J 0
(-3375 4975);
DISPLAY 0.872340 (-3375 4975);
PAINT GREEN (-3375 4975);
DISPLAY INVISIBLE (-3375 4975);
FORCEPROP 1 LAST HDL_TAP TRUE
J 0
(-3050 4800);
DISPLAY 0.872340 (-3050 4800);
DISPLAY INVISIBLE (-3050 4800);
FORCEPROP 1 LAST PATH I181
J 0
(-3377 4925);
DISPLAY 0.872340 (-3377 4925);
PAINT GREEN (-3377 4925);
DISPLAY INVISIBLE (-3377 4925);
FORCEADD TAP..1
(-3375 4975);
FORCEPROP 3 LASTPIN (-3425 4975) SIG_NAME M_F_CPU0_SA_DQ<18>
J 0
(-3415 4985);
DISPLAY 0.659574 (-3415 4985);
PAINT MONO (-3415 4985);
DISPLAY INVISIBLE (-3415 4985);
FORCEPROP 1 LASTPIN (-3425 4975) BN 18
J 0
(-3437 4983);
DISPLAY 0.489362 (-3437 4983);
PAINT GREEN (-3437 4983);
FORCEPROP 2 LAST CDS_LIB mstr_standard
J 0
(-3375 4975);
DISPLAY 0.723404 (-3375 4975);
PAINT MONO (-3375 4975);
DISPLAY INVISIBLE (-3375 4975);
FORCEPROP 1 LAST BODY_TYPE PLUMBING
J 0
(-3375 5025);
DISPLAY 0.872340 (-3375 5025);
PAINT GREEN (-3375 5025);
DISPLAY INVISIBLE (-3375 5025);
FORCEPROP 1 LAST HDL_TAP TRUE
J 0
(-3050 4850);
DISPLAY 0.872340 (-3050 4850);
DISPLAY INVISIBLE (-3050 4850);
FORCEPROP 1 LAST PATH I182
J 0
(-3377 4975);
DISPLAY 0.872340 (-3377 4975);
PAINT GREEN (-3377 4975);
DISPLAY INVISIBLE (-3377 4975);
FORCEADD TAP..1
(-3375 4775);
FORCEPROP 3 LASTPIN (-3425 4775) SIG_NAME M_F_CPU0_SA_DQ<22>
J 0
(-3415 4785);
DISPLAY 0.659574 (-3415 4785);
PAINT MONO (-3415 4785);
DISPLAY INVISIBLE (-3415 4785);
FORCEPROP 1 LASTPIN (-3425 4775) BN 22
J 0
(-3437 4783);
DISPLAY 0.489362 (-3437 4783);
PAINT GREEN (-3437 4783);
FORCEPROP 2 LAST CDS_LIB mstr_standard
J 0
(-3375 4775);
DISPLAY 0.723404 (-3375 4775);
PAINT MONO (-3375 4775);
DISPLAY INVISIBLE (-3375 4775);
FORCEPROP 1 LAST BODY_TYPE PLUMBING
J 0
(-3375 4825);
DISPLAY 0.872340 (-3375 4825);
PAINT GREEN (-3375 4825);
DISPLAY INVISIBLE (-3375 4825);
FORCEPROP 1 LAST HDL_TAP TRUE
J 0
(-3050 4650);
DISPLAY 0.872340 (-3050 4650);
DISPLAY INVISIBLE (-3050 4650);
FORCEPROP 1 LAST PATH I183
J 0
(-3377 4775);
DISPLAY 0.872340 (-3377 4775);
PAINT GREEN (-3377 4775);
DISPLAY INVISIBLE (-3377 4775);
FORCEADD TAP..1
(-3375 4825);
FORCEPROP 3 LASTPIN (-3425 4825) SIG_NAME M_F_CPU0_SA_DQ<21>
J 0
(-3415 4835);
DISPLAY 0.659574 (-3415 4835);
PAINT MONO (-3415 4835);
DISPLAY INVISIBLE (-3415 4835);
FORCEPROP 1 LASTPIN (-3425 4825) BN 21
J 0
(-3437 4833);
DISPLAY 0.489362 (-3437 4833);
PAINT GREEN (-3437 4833);
FORCEPROP 2 LAST CDS_LIB mstr_standard
J 0
(-3375 4825);
DISPLAY 0.723404 (-3375 4825);
PAINT MONO (-3375 4825);
DISPLAY INVISIBLE (-3375 4825);
FORCEPROP 1 LAST BODY_TYPE PLUMBING
J 0
(-3375 4875);
DISPLAY 0.872340 (-3375 4875);
PAINT GREEN (-3375 4875);
DISPLAY INVISIBLE (-3375 4875);
FORCEPROP 1 LAST HDL_TAP TRUE
J 0
(-3050 4700);
DISPLAY 0.872340 (-3050 4700);
DISPLAY INVISIBLE (-3050 4700);
FORCEPROP 1 LAST PATH I184
J 0
(-3377 4825);
DISPLAY 0.872340 (-3377 4825);
PAINT GREEN (-3377 4825);
DISPLAY INVISIBLE (-3377 4825);
FORCEADD TAP..1
(-3375 4725);
FORCEPROP 3 LASTPIN (-3425 4725) SIG_NAME M_F_CPU0_SA_DQ<23>
J 0
(-3415 4735);
DISPLAY 0.659574 (-3415 4735);
PAINT MONO (-3415 4735);
DISPLAY INVISIBLE (-3415 4735);
FORCEPROP 1 LASTPIN (-3425 4725) BN 23
J 0
(-3437 4733);
DISPLAY 0.489362 (-3437 4733);
PAINT GREEN (-3437 4733);
FORCEPROP 2 LAST CDS_LIB mstr_standard
J 0
(-3375 4725);
DISPLAY 0.723404 (-3375 4725);
PAINT MONO (-3375 4725);
DISPLAY INVISIBLE (-3375 4725);
FORCEPROP 1 LAST BODY_TYPE PLUMBING
J 0
(-3375 4775);
DISPLAY 0.872340 (-3375 4775);
PAINT GREEN (-3375 4775);
DISPLAY INVISIBLE (-3375 4775);
FORCEPROP 1 LAST HDL_TAP TRUE
J 0
(-3050 4600);
DISPLAY 0.872340 (-3050 4600);
DISPLAY INVISIBLE (-3050 4600);
FORCEPROP 1 LAST PATH I185
J 0
(-3377 4725);
DISPLAY 0.872340 (-3377 4725);
PAINT GREEN (-3377 4725);
DISPLAY INVISIBLE (-3377 4725);
FORCEADD TAP..1
(-3375 4625);
FORCEPROP 3 LASTPIN (-3425 4625) SIG_NAME M_F_CPU0_SA_DQ<24>
J 0
(-3415 4635);
DISPLAY 0.659574 (-3415 4635);
PAINT MONO (-3415 4635);
DISPLAY INVISIBLE (-3415 4635);
FORCEPROP 1 LASTPIN (-3425 4625) BN 24
J 0
(-3437 4633);
DISPLAY 0.489362 (-3437 4633);
PAINT GREEN (-3437 4633);
FORCEPROP 2 LAST CDS_LIB mstr_standard
J 0
(-3375 4625);
DISPLAY 0.723404 (-3375 4625);
PAINT MONO (-3375 4625);
DISPLAY INVISIBLE (-3375 4625);
FORCEPROP 1 LAST BODY_TYPE PLUMBING
J 0
(-3375 4675);
DISPLAY 0.872340 (-3375 4675);
PAINT GREEN (-3375 4675);
DISPLAY INVISIBLE (-3375 4675);
FORCEPROP 1 LAST HDL_TAP TRUE
J 0
(-3050 4500);
DISPLAY 0.872340 (-3050 4500);
DISPLAY INVISIBLE (-3050 4500);
FORCEPROP 1 LAST PATH I186
J 0
(-3377 4625);
DISPLAY 0.872340 (-3377 4625);
PAINT GREEN (-3377 4625);
DISPLAY INVISIBLE (-3377 4625);
FORCEADD TAP..1
(-3375 4575);
FORCEPROP 3 LASTPIN (-3425 4575) SIG_NAME M_F_CPU0_SA_DQ<25>
J 0
(-3415 4585);
DISPLAY 0.659574 (-3415 4585);
PAINT MONO (-3415 4585);
DISPLAY INVISIBLE (-3415 4585);
FORCEPROP 1 LASTPIN (-3425 4575) BN 25
J 0
(-3437 4583);
DISPLAY 0.489362 (-3437 4583);
PAINT GREEN (-3437 4583);
FORCEPROP 2 LAST CDS_LIB mstr_standard
J 0
(-3375 4575);
DISPLAY 0.723404 (-3375 4575);
PAINT MONO (-3375 4575);
DISPLAY INVISIBLE (-3375 4575);
FORCEPROP 1 LAST BODY_TYPE PLUMBING
J 0
(-3375 4625);
DISPLAY 0.872340 (-3375 4625);
PAINT GREEN (-3375 4625);
DISPLAY INVISIBLE (-3375 4625);
FORCEPROP 1 LAST HDL_TAP TRUE
J 0
(-3050 4450);
DISPLAY 0.872340 (-3050 4450);
DISPLAY INVISIBLE (-3050 4450);
FORCEPROP 1 LAST PATH I187
J 0
(-3377 4575);
DISPLAY 0.872340 (-3377 4575);
PAINT GREEN (-3377 4575);
DISPLAY INVISIBLE (-3377 4575);
FORCEADD TAP..1
(-3375 4525);
FORCEPROP 3 LASTPIN (-3425 4525) SIG_NAME M_F_CPU0_SA_DQ<26>
J 0
(-3415 4535);
DISPLAY 0.659574 (-3415 4535);
PAINT MONO (-3415 4535);
DISPLAY INVISIBLE (-3415 4535);
FORCEPROP 1 LASTPIN (-3425 4525) BN 26
J 0
(-3437 4533);
DISPLAY 0.489362 (-3437 4533);
PAINT GREEN (-3437 4533);
FORCEPROP 2 LAST CDS_LIB mstr_standard
J 0
(-3375 4525);
DISPLAY 0.723404 (-3375 4525);
PAINT MONO (-3375 4525);
DISPLAY INVISIBLE (-3375 4525);
FORCEPROP 1 LAST BODY_TYPE PLUMBING
J 0
(-3375 4575);
DISPLAY 0.872340 (-3375 4575);
PAINT GREEN (-3375 4575);
DISPLAY INVISIBLE (-3375 4575);
FORCEPROP 1 LAST HDL_TAP TRUE
J 0
(-3050 4400);
DISPLAY 0.872340 (-3050 4400);
DISPLAY INVISIBLE (-3050 4400);
FORCEPROP 1 LAST PATH I188
J 0
(-3377 4525);
DISPLAY 0.872340 (-3377 4525);
PAINT GREEN (-3377 4525);
DISPLAY INVISIBLE (-3377 4525);
FORCEADD TAP..1
(-3375 4375);
FORCEPROP 3 LASTPIN (-3425 4375) SIG_NAME M_F_CPU0_SA_DQ<29>
J 0
(-3415 4385);
DISPLAY 0.659574 (-3415 4385);
PAINT MONO (-3415 4385);
DISPLAY INVISIBLE (-3415 4385);
FORCEPROP 1 LASTPIN (-3425 4375) BN 29
J 0
(-3437 4383);
DISPLAY 0.489362 (-3437 4383);
PAINT GREEN (-3437 4383);
FORCEPROP 2 LAST CDS_LIB mstr_standard
J 0
(-3375 4375);
DISPLAY 0.723404 (-3375 4375);
PAINT MONO (-3375 4375);
DISPLAY INVISIBLE (-3375 4375);
FORCEPROP 1 LAST BODY_TYPE PLUMBING
J 0
(-3375 4425);
DISPLAY 0.872340 (-3375 4425);
PAINT GREEN (-3375 4425);
DISPLAY INVISIBLE (-3375 4425);
FORCEPROP 1 LAST HDL_TAP TRUE
J 0
(-3050 4250);
DISPLAY 0.872340 (-3050 4250);
DISPLAY INVISIBLE (-3050 4250);
FORCEPROP 1 LAST PATH I189
J 0
(-3377 4375);
DISPLAY 0.872340 (-3377 4375);
PAINT GREEN (-3377 4375);
DISPLAY INVISIBLE (-3377 4375);
FORCEADD TAP..1
(-3375 4425);
FORCEPROP 3 LASTPIN (-3425 4425) SIG_NAME M_F_CPU0_SA_DQ<28>
J 0
(-3415 4435);
DISPLAY 0.659574 (-3415 4435);
PAINT MONO (-3415 4435);
DISPLAY INVISIBLE (-3415 4435);
FORCEPROP 1 LASTPIN (-3425 4425) BN 28
J 0
(-3437 4433);
DISPLAY 0.489362 (-3437 4433);
PAINT GREEN (-3437 4433);
FORCEPROP 2 LAST CDS_LIB mstr_standard
J 0
(-3375 4425);
DISPLAY 0.723404 (-3375 4425);
PAINT MONO (-3375 4425);
DISPLAY INVISIBLE (-3375 4425);
FORCEPROP 1 LAST BODY_TYPE PLUMBING
J 0
(-3375 4475);
DISPLAY 0.872340 (-3375 4475);
PAINT GREEN (-3375 4475);
DISPLAY INVISIBLE (-3375 4475);
FORCEPROP 1 LAST HDL_TAP TRUE
J 0
(-3050 4300);
DISPLAY 0.872340 (-3050 4300);
DISPLAY INVISIBLE (-3050 4300);
FORCEPROP 1 LAST PATH I190
J 0
(-3377 4425);
DISPLAY 0.872340 (-3377 4425);
PAINT GREEN (-3377 4425);
DISPLAY INVISIBLE (-3377 4425);
FORCEADD TAP..1
(-3375 4475);
FORCEPROP 3 LASTPIN (-3425 4475) SIG_NAME M_F_CPU0_SA_DQ<27>
J 0
(-3415 4485);
DISPLAY 0.659574 (-3415 4485);
PAINT MONO (-3415 4485);
DISPLAY INVISIBLE (-3415 4485);
FORCEPROP 1 LASTPIN (-3425 4475) BN 27
J 0
(-3437 4483);
DISPLAY 0.489362 (-3437 4483);
PAINT GREEN (-3437 4483);
FORCEPROP 2 LAST CDS_LIB mstr_standard
J 0
(-3375 4475);
DISPLAY 0.723404 (-3375 4475);
PAINT MONO (-3375 4475);
DISPLAY INVISIBLE (-3375 4475);
FORCEPROP 1 LAST BODY_TYPE PLUMBING
J 0
(-3375 4525);
DISPLAY 0.872340 (-3375 4525);
PAINT GREEN (-3375 4525);
DISPLAY INVISIBLE (-3375 4525);
FORCEPROP 1 LAST HDL_TAP TRUE
J 0
(-3050 4350);
DISPLAY 0.872340 (-3050 4350);
DISPLAY INVISIBLE (-3050 4350);
FORCEPROP 1 LAST PATH I191
J 0
(-3377 4475);
DISPLAY 0.872340 (-3377 4475);
PAINT GREEN (-3377 4475);
DISPLAY INVISIBLE (-3377 4475);
FORCEADD TAP..1
(-3375 4275);
FORCEPROP 3 LASTPIN (-3425 4275) SIG_NAME M_F_CPU0_SA_DQ<31>
J 0
(-3415 4285);
DISPLAY 0.659574 (-3415 4285);
PAINT MONO (-3415 4285);
DISPLAY INVISIBLE (-3415 4285);
FORCEPROP 1 LASTPIN (-3425 4275) BN 31
J 0
(-3437 4283);
DISPLAY 0.489362 (-3437 4283);
PAINT GREEN (-3437 4283);
FORCEPROP 2 LAST CDS_LIB mstr_standard
J 0
(-3375 4275);
DISPLAY 0.723404 (-3375 4275);
PAINT MONO (-3375 4275);
DISPLAY INVISIBLE (-3375 4275);
FORCEPROP 1 LAST BODY_TYPE PLUMBING
J 0
(-3375 4325);
DISPLAY 0.872340 (-3375 4325);
PAINT GREEN (-3375 4325);
DISPLAY INVISIBLE (-3375 4325);
FORCEPROP 1 LAST HDL_TAP TRUE
J 0
(-3050 4150);
DISPLAY 0.872340 (-3050 4150);
DISPLAY INVISIBLE (-3050 4150);
FORCEPROP 1 LAST PATH I192
J 0
(-3377 4275);
DISPLAY 0.872340 (-3377 4275);
PAINT GREEN (-3377 4275);
DISPLAY INVISIBLE (-3377 4275);
FORCEADD TAP..1
(-3375 4325);
FORCEPROP 3 LASTPIN (-3425 4325) SIG_NAME M_F_CPU0_SA_DQ<30>
J 0
(-3415 4335);
DISPLAY 0.659574 (-3415 4335);
PAINT MONO (-3415 4335);
DISPLAY INVISIBLE (-3415 4335);
FORCEPROP 1 LASTPIN (-3425 4325) BN 30
J 0
(-3437 4333);
DISPLAY 0.489362 (-3437 4333);
PAINT GREEN (-3437 4333);
FORCEPROP 2 LAST CDS_LIB mstr_standard
J 0
(-3375 4325);
DISPLAY 0.723404 (-3375 4325);
PAINT MONO (-3375 4325);
DISPLAY INVISIBLE (-3375 4325);
FORCEPROP 1 LAST BODY_TYPE PLUMBING
J 0
(-3375 4375);
DISPLAY 0.872340 (-3375 4375);
PAINT GREEN (-3375 4375);
DISPLAY INVISIBLE (-3375 4375);
FORCEPROP 1 LAST HDL_TAP TRUE
J 0
(-3050 4200);
DISPLAY 0.872340 (-3050 4200);
DISPLAY INVISIBLE (-3050 4200);
FORCEPROP 1 LAST PATH I193
J 0
(-3377 4325);
DISPLAY 0.872340 (-3377 4325);
PAINT GREEN (-3377 4325);
DISPLAY INVISIBLE (-3377 4325);
FORCEADD TAP..1
(-3375 4125);
FORCEPROP 3 LASTPIN (-3425 4125) SIG_NAME M_F_CPU0_SB_DQ<1>
J 0
(-3415 4135);
DISPLAY 0.659574 (-3415 4135);
PAINT MONO (-3415 4135);
DISPLAY INVISIBLE (-3415 4135);
FORCEPROP 1 LASTPIN (-3425 4125) BN 1
J 0
(-3437 4133);
DISPLAY 0.489362 (-3437 4133);
PAINT GREEN (-3437 4133);
FORCEPROP 2 LAST CDS_LIB mstr_standard
J 0
(-3375 4125);
DISPLAY 0.723404 (-3375 4125);
PAINT MONO (-3375 4125);
DISPLAY INVISIBLE (-3375 4125);
FORCEPROP 1 LAST BODY_TYPE PLUMBING
J 0
(-3375 4175);
DISPLAY 0.872340 (-3375 4175);
PAINT GREEN (-3375 4175);
DISPLAY INVISIBLE (-3375 4175);
FORCEPROP 1 LAST HDL_TAP TRUE
J 0
(-3050 4000);
DISPLAY 0.872340 (-3050 4000);
DISPLAY INVISIBLE (-3050 4000);
FORCEPROP 1 LAST PATH I194
J 0
(-3377 4125);
DISPLAY 0.872340 (-3377 4125);
PAINT GREEN (-3377 4125);
DISPLAY INVISIBLE (-3377 4125);
FORCEADD TAP..1
(-3375 4175);
FORCEPROP 3 LASTPIN (-3425 4175) SIG_NAME M_F_CPU0_SB_DQ<0>
J 0
(-3415 4185);
DISPLAY 0.659574 (-3415 4185);
PAINT MONO (-3415 4185);
DISPLAY INVISIBLE (-3415 4185);
FORCEPROP 1 LASTPIN (-3425 4175) BN 0
J 0
(-3437 4183);
DISPLAY 0.489362 (-3437 4183);
PAINT GREEN (-3437 4183);
FORCEPROP 2 LAST CDS_LIB mstr_standard
J 0
(-3375 4175);
DISPLAY 0.723404 (-3375 4175);
PAINT MONO (-3375 4175);
DISPLAY INVISIBLE (-3375 4175);
FORCEPROP 1 LAST BODY_TYPE PLUMBING
J 0
(-3375 4225);
DISPLAY 0.872340 (-3375 4225);
PAINT GREEN (-3375 4225);
DISPLAY INVISIBLE (-3375 4225);
FORCEPROP 1 LAST HDL_TAP TRUE
J 0
(-3050 4050);
DISPLAY 0.872340 (-3050 4050);
DISPLAY INVISIBLE (-3050 4050);
FORCEPROP 1 LAST PATH I195
J 0
(-3377 4175);
DISPLAY 0.872340 (-3377 4175);
PAINT GREEN (-3377 4175);
DISPLAY INVISIBLE (-3377 4175);
FORCEADD OFFPAGE..6
R 2
(-2775 2425);
FORCEPROP 2 LAST $XR0 90 
J 0
(-2561 2425);
DISPLAY 0.638298 (-2561 2425);
PAINT MONO (-2561 2425);
FORCEPROP 2 LAST PATH I196
J 0
(-2550 2475);
DISPLAY 1.021277 (-2550 2475);
DISPLAY INVISIBLE (-2550 2475);
FORCEPROP 1 LAST COMMENT_BODY TRUE
J 2
(-2875 2350);
DISPLAY 0.872340 (-2875 2350);
PAINT GREEN (-2875 2350);
DISPLAY INVISIBLE (-2875 2350);
FORCEPROP 1 LAST OFFPAGE TRUE
J 2
(-3100 2300);
DISPLAY 0.872340 (-3100 2300);
PAINT GREEN (-3100 2300);
DISPLAY INVISIBLE (-3100 2300);
FORCEPROP 2 LAST CDS_LIB mstr_standard
J 2
(-2775 2425);
DISPLAY 0.723404 (-2775 2425);
PAINT MONO (-2775 2425);
DISPLAY INVISIBLE (-2775 2425);
FORCEADD TAP..1
(-3375 3975);
FORCEPROP 3 LASTPIN (-3425 3975) SIG_NAME M_F_CPU0_SB_DQ<4>
J 0
(-3415 3985);
DISPLAY 0.659574 (-3415 3985);
PAINT MONO (-3415 3985);
DISPLAY INVISIBLE (-3415 3985);
FORCEPROP 1 LASTPIN (-3425 3975) BN 4
J 0
(-3437 3983);
DISPLAY 0.489362 (-3437 3983);
PAINT GREEN (-3437 3983);
FORCEPROP 2 LAST CDS_LIB mstr_standard
J 0
(-3375 3975);
DISPLAY 0.723404 (-3375 3975);
PAINT MONO (-3375 3975);
DISPLAY INVISIBLE (-3375 3975);
FORCEPROP 1 LAST BODY_TYPE PLUMBING
J 0
(-3375 4025);
DISPLAY 0.872340 (-3375 4025);
PAINT GREEN (-3375 4025);
DISPLAY INVISIBLE (-3375 4025);
FORCEPROP 1 LAST HDL_TAP TRUE
J 0
(-3050 3850);
DISPLAY 0.872340 (-3050 3850);
DISPLAY INVISIBLE (-3050 3850);
FORCEPROP 1 LAST PATH I197
J 0
(-3377 3975);
DISPLAY 0.872340 (-3377 3975);
PAINT GREEN (-3377 3975);
DISPLAY INVISIBLE (-3377 3975);
FORCEADD TAP..1
(-3375 4025);
FORCEPROP 3 LASTPIN (-3425 4025) SIG_NAME M_F_CPU0_SB_DQ<3>
J 0
(-3415 4035);
DISPLAY 0.659574 (-3415 4035);
PAINT MONO (-3415 4035);
DISPLAY INVISIBLE (-3415 4035);
FORCEPROP 1 LASTPIN (-3425 4025) BN 3
J 0
(-3437 4033);
DISPLAY 0.489362 (-3437 4033);
PAINT GREEN (-3437 4033);
FORCEPROP 2 LAST CDS_LIB mstr_standard
J 0
(-3375 4025);
DISPLAY 0.723404 (-3375 4025);
PAINT MONO (-3375 4025);
DISPLAY INVISIBLE (-3375 4025);
FORCEPROP 1 LAST BODY_TYPE PLUMBING
J 0
(-3375 4075);
DISPLAY 0.872340 (-3375 4075);
PAINT GREEN (-3375 4075);
DISPLAY INVISIBLE (-3375 4075);
FORCEPROP 1 LAST HDL_TAP TRUE
J 0
(-3050 3900);
DISPLAY 0.872340 (-3050 3900);
DISPLAY INVISIBLE (-3050 3900);
FORCEPROP 1 LAST PATH I198
J 0
(-3377 4025);
DISPLAY 0.872340 (-3377 4025);
PAINT GREEN (-3377 4025);
DISPLAY INVISIBLE (-3377 4025);
FORCEADD TAP..1
(-3375 4075);
FORCEPROP 3 LASTPIN (-3425 4075) SIG_NAME M_F_CPU0_SB_DQ<2>
J 0
(-3415 4085);
DISPLAY 0.659574 (-3415 4085);
PAINT MONO (-3415 4085);
DISPLAY INVISIBLE (-3415 4085);
FORCEPROP 1 LASTPIN (-3425 4075) BN 2
J 0
(-3437 4083);
DISPLAY 0.489362 (-3437 4083);
PAINT GREEN (-3437 4083);
FORCEPROP 2 LAST CDS_LIB mstr_standard
J 0
(-3375 4075);
DISPLAY 0.723404 (-3375 4075);
PAINT MONO (-3375 4075);
DISPLAY INVISIBLE (-3375 4075);
FORCEPROP 1 LAST BODY_TYPE PLUMBING
J 0
(-3375 4125);
DISPLAY 0.872340 (-3375 4125);
PAINT GREEN (-3375 4125);
DISPLAY INVISIBLE (-3375 4125);
FORCEPROP 1 LAST HDL_TAP TRUE
J 0
(-3050 3950);
DISPLAY 0.872340 (-3050 3950);
DISPLAY INVISIBLE (-3050 3950);
FORCEPROP 1 LAST PATH I199
J 0
(-3377 4075);
DISPLAY 0.872340 (-3377 4075);
PAINT GREEN (-3377 4075);
DISPLAY INVISIBLE (-3377 4075);
FORCEADD TAP..1
(-3375 3875);
FORCEPROP 3 LASTPIN (-3425 3875) SIG_NAME M_F_CPU0_SB_DQ<6>
J 0
(-3415 3885);
DISPLAY 0.659574 (-3415 3885);
PAINT MONO (-3415 3885);
DISPLAY INVISIBLE (-3415 3885);
FORCEPROP 1 LASTPIN (-3425 3875) BN 6
J 0
(-3437 3883);
DISPLAY 0.489362 (-3437 3883);
PAINT GREEN (-3437 3883);
FORCEPROP 2 LAST CDS_LIB mstr_standard
J 0
(-3375 3875);
DISPLAY 0.723404 (-3375 3875);
PAINT MONO (-3375 3875);
DISPLAY INVISIBLE (-3375 3875);
FORCEPROP 1 LAST BODY_TYPE PLUMBING
J 0
(-3375 3925);
DISPLAY 0.872340 (-3375 3925);
PAINT GREEN (-3375 3925);
DISPLAY INVISIBLE (-3375 3925);
FORCEPROP 1 LAST HDL_TAP TRUE
J 0
(-3050 3750);
DISPLAY 0.872340 (-3050 3750);
DISPLAY INVISIBLE (-3050 3750);
FORCEPROP 1 LAST PATH I200
J 0
(-3377 3875);
DISPLAY 0.872340 (-3377 3875);
PAINT GREEN (-3377 3875);
DISPLAY INVISIBLE (-3377 3875);
FORCEADD TAP..1
(-3375 3925);
FORCEPROP 3 LASTPIN (-3425 3925) SIG_NAME M_F_CPU0_SB_DQ<5>
J 0
(-3415 3935);
DISPLAY 0.659574 (-3415 3935);
PAINT MONO (-3415 3935);
DISPLAY INVISIBLE (-3415 3935);
FORCEPROP 1 LASTPIN (-3425 3925) BN 5
J 0
(-3437 3933);
DISPLAY 0.489362 (-3437 3933);
PAINT GREEN (-3437 3933);
FORCEPROP 2 LAST CDS_LIB mstr_standard
J 0
(-3375 3925);
DISPLAY 0.723404 (-3375 3925);
PAINT MONO (-3375 3925);
DISPLAY INVISIBLE (-3375 3925);
FORCEPROP 1 LAST BODY_TYPE PLUMBING
J 0
(-3375 3975);
DISPLAY 0.872340 (-3375 3975);
PAINT GREEN (-3375 3975);
DISPLAY INVISIBLE (-3375 3975);
FORCEPROP 1 LAST HDL_TAP TRUE
J 0
(-3050 3800);
DISPLAY 0.872340 (-3050 3800);
DISPLAY INVISIBLE (-3050 3800);
FORCEPROP 1 LAST PATH I201
J 0
(-3377 3925);
DISPLAY 0.872340 (-3377 3925);
PAINT GREEN (-3377 3925);
DISPLAY INVISIBLE (-3377 3925);
FORCEADD TAP..1
(-3375 3725);
FORCEPROP 3 LASTPIN (-3425 3725) SIG_NAME M_F_CPU0_SB_DQ<8>
J 0
(-3415 3735);
DISPLAY 0.659574 (-3415 3735);
PAINT MONO (-3415 3735);
DISPLAY INVISIBLE (-3415 3735);
FORCEPROP 1 LASTPIN (-3425 3725) BN 8
J 0
(-3437 3733);
DISPLAY 0.489362 (-3437 3733);
PAINT GREEN (-3437 3733);
FORCEPROP 2 LAST CDS_LIB mstr_standard
J 0
(-3375 3725);
DISPLAY 0.723404 (-3375 3725);
PAINT MONO (-3375 3725);
DISPLAY INVISIBLE (-3375 3725);
FORCEPROP 1 LAST BODY_TYPE PLUMBING
J 0
(-3375 3775);
DISPLAY 0.872340 (-3375 3775);
PAINT GREEN (-3375 3775);
DISPLAY INVISIBLE (-3375 3775);
FORCEPROP 1 LAST HDL_TAP TRUE
J 0
(-3050 3600);
DISPLAY 0.872340 (-3050 3600);
DISPLAY INVISIBLE (-3050 3600);
FORCEPROP 1 LAST PATH I202
J 0
(-3377 3725);
DISPLAY 0.872340 (-3377 3725);
PAINT GREEN (-3377 3725);
DISPLAY INVISIBLE (-3377 3725);
FORCEADD TAP..1
(-3375 3825);
FORCEPROP 3 LASTPIN (-3425 3825) SIG_NAME M_F_CPU0_SB_DQ<7>
J 0
(-3415 3835);
DISPLAY 0.659574 (-3415 3835);
PAINT MONO (-3415 3835);
DISPLAY INVISIBLE (-3415 3835);
FORCEPROP 1 LASTPIN (-3425 3825) BN 7
J 0
(-3437 3833);
DISPLAY 0.489362 (-3437 3833);
PAINT GREEN (-3437 3833);
FORCEPROP 2 LAST CDS_LIB mstr_standard
J 0
(-3375 3825);
DISPLAY 0.723404 (-3375 3825);
PAINT MONO (-3375 3825);
DISPLAY INVISIBLE (-3375 3825);
FORCEPROP 1 LAST BODY_TYPE PLUMBING
J 0
(-3375 3875);
DISPLAY 0.872340 (-3375 3875);
PAINT GREEN (-3375 3875);
DISPLAY INVISIBLE (-3375 3875);
FORCEPROP 1 LAST HDL_TAP TRUE
J 0
(-3050 3700);
DISPLAY 0.872340 (-3050 3700);
DISPLAY INVISIBLE (-3050 3700);
FORCEPROP 1 LAST PATH I203
J 0
(-3377 3825);
DISPLAY 0.872340 (-3377 3825);
PAINT GREEN (-3377 3825);
DISPLAY INVISIBLE (-3377 3825);
FORCEADD TAP..1
(-3375 3625);
FORCEPROP 3 LASTPIN (-3425 3625) SIG_NAME M_F_CPU0_SB_DQ<10>
J 0
(-3415 3635);
DISPLAY 0.659574 (-3415 3635);
PAINT MONO (-3415 3635);
DISPLAY INVISIBLE (-3415 3635);
FORCEPROP 1 LASTPIN (-3425 3625) BN 10
J 0
(-3437 3633);
DISPLAY 0.489362 (-3437 3633);
PAINT GREEN (-3437 3633);
FORCEPROP 2 LAST CDS_LIB mstr_standard
J 0
(-3375 3625);
DISPLAY 0.723404 (-3375 3625);
PAINT MONO (-3375 3625);
DISPLAY INVISIBLE (-3375 3625);
FORCEPROP 1 LAST BODY_TYPE PLUMBING
J 0
(-3375 3675);
DISPLAY 0.872340 (-3375 3675);
PAINT GREEN (-3375 3675);
DISPLAY INVISIBLE (-3375 3675);
FORCEPROP 1 LAST HDL_TAP TRUE
J 0
(-3050 3500);
DISPLAY 0.872340 (-3050 3500);
DISPLAY INVISIBLE (-3050 3500);
FORCEPROP 1 LAST PATH I204
J 0
(-3377 3625);
DISPLAY 0.872340 (-3377 3625);
PAINT GREEN (-3377 3625);
DISPLAY INVISIBLE (-3377 3625);
FORCEADD TAP..1
(-3375 3675);
FORCEPROP 3 LASTPIN (-3425 3675) SIG_NAME M_F_CPU0_SB_DQ<9>
J 0
(-3415 3685);
DISPLAY 0.659574 (-3415 3685);
PAINT MONO (-3415 3685);
DISPLAY INVISIBLE (-3415 3685);
FORCEPROP 1 LASTPIN (-3425 3675) BN 9
J 0
(-3437 3683);
DISPLAY 0.489362 (-3437 3683);
PAINT GREEN (-3437 3683);
FORCEPROP 2 LAST CDS_LIB mstr_standard
J 0
(-3375 3675);
DISPLAY 0.723404 (-3375 3675);
PAINT MONO (-3375 3675);
DISPLAY INVISIBLE (-3375 3675);
FORCEPROP 1 LAST BODY_TYPE PLUMBING
J 0
(-3375 3725);
DISPLAY 0.872340 (-3375 3725);
PAINT GREEN (-3375 3725);
DISPLAY INVISIBLE (-3375 3725);
FORCEPROP 1 LAST HDL_TAP TRUE
J 0
(-3050 3550);
DISPLAY 0.872340 (-3050 3550);
DISPLAY INVISIBLE (-3050 3550);
FORCEPROP 1 LAST PATH I205
J 0
(-3377 3675);
DISPLAY 0.872340 (-3377 3675);
PAINT GREEN (-3377 3675);
DISPLAY INVISIBLE (-3377 3675);
FORCEADD TAP..1
(-3375 3475);
FORCEPROP 3 LASTPIN (-3425 3475) SIG_NAME M_F_CPU0_SB_DQ<13>
J 0
(-3415 3485);
DISPLAY 0.659574 (-3415 3485);
PAINT MONO (-3415 3485);
DISPLAY INVISIBLE (-3415 3485);
FORCEPROP 1 LASTPIN (-3425 3475) BN 13
J 0
(-3437 3483);
DISPLAY 0.489362 (-3437 3483);
PAINT GREEN (-3437 3483);
FORCEPROP 2 LAST CDS_LIB mstr_standard
J 0
(-3375 3475);
DISPLAY 0.723404 (-3375 3475);
PAINT MONO (-3375 3475);
DISPLAY INVISIBLE (-3375 3475);
FORCEPROP 1 LAST BODY_TYPE PLUMBING
J 0
(-3375 3525);
DISPLAY 0.872340 (-3375 3525);
PAINT GREEN (-3375 3525);
DISPLAY INVISIBLE (-3375 3525);
FORCEPROP 1 LAST HDL_TAP TRUE
J 0
(-3050 3350);
DISPLAY 0.872340 (-3050 3350);
DISPLAY INVISIBLE (-3050 3350);
FORCEPROP 1 LAST PATH I206
J 0
(-3377 3475);
DISPLAY 0.872340 (-3377 3475);
PAINT GREEN (-3377 3475);
DISPLAY INVISIBLE (-3377 3475);
FORCEADD TAP..1
(-3375 3525);
FORCEPROP 3 LASTPIN (-3425 3525) SIG_NAME M_F_CPU0_SB_DQ<12>
J 0
(-3415 3535);
DISPLAY 0.659574 (-3415 3535);
PAINT MONO (-3415 3535);
DISPLAY INVISIBLE (-3415 3535);
FORCEPROP 1 LASTPIN (-3425 3525) BN 12
J 0
(-3437 3533);
DISPLAY 0.489362 (-3437 3533);
PAINT GREEN (-3437 3533);
FORCEPROP 2 LAST CDS_LIB mstr_standard
J 0
(-3375 3525);
DISPLAY 0.723404 (-3375 3525);
PAINT MONO (-3375 3525);
DISPLAY INVISIBLE (-3375 3525);
FORCEPROP 1 LAST BODY_TYPE PLUMBING
J 0
(-3375 3575);
DISPLAY 0.872340 (-3375 3575);
PAINT GREEN (-3375 3575);
DISPLAY INVISIBLE (-3375 3575);
FORCEPROP 1 LAST HDL_TAP TRUE
J 0
(-3050 3400);
DISPLAY 0.872340 (-3050 3400);
DISPLAY INVISIBLE (-3050 3400);
FORCEPROP 1 LAST PATH I207
J 0
(-3377 3525);
DISPLAY 0.872340 (-3377 3525);
PAINT GREEN (-3377 3525);
DISPLAY INVISIBLE (-3377 3525);
FORCEADD TAP..1
(-3375 3575);
FORCEPROP 3 LASTPIN (-3425 3575) SIG_NAME M_F_CPU0_SB_DQ<11>
J 0
(-3415 3585);
DISPLAY 0.659574 (-3415 3585);
PAINT MONO (-3415 3585);
DISPLAY INVISIBLE (-3415 3585);
FORCEPROP 1 LASTPIN (-3425 3575) BN 11
J 0
(-3437 3583);
DISPLAY 0.489362 (-3437 3583);
PAINT GREEN (-3437 3583);
FORCEPROP 2 LAST CDS_LIB mstr_standard
J 0
(-3375 3575);
DISPLAY 0.723404 (-3375 3575);
PAINT MONO (-3375 3575);
DISPLAY INVISIBLE (-3375 3575);
FORCEPROP 1 LAST BODY_TYPE PLUMBING
J 0
(-3375 3625);
DISPLAY 0.872340 (-3375 3625);
PAINT GREEN (-3375 3625);
DISPLAY INVISIBLE (-3375 3625);
FORCEPROP 1 LAST HDL_TAP TRUE
J 0
(-3050 3450);
DISPLAY 0.872340 (-3050 3450);
DISPLAY INVISIBLE (-3050 3450);
FORCEPROP 1 LAST PATH I208
J 0
(-3377 3575);
DISPLAY 0.872340 (-3377 3575);
PAINT GREEN (-3377 3575);
DISPLAY INVISIBLE (-3377 3575);
FORCEADD TAP..1
(-3375 3425);
FORCEPROP 3 LASTPIN (-3425 3425) SIG_NAME M_F_CPU0_SB_DQ<14>
J 0
(-3415 3435);
DISPLAY 0.659574 (-3415 3435);
PAINT MONO (-3415 3435);
DISPLAY INVISIBLE (-3415 3435);
FORCEPROP 1 LASTPIN (-3425 3425) BN 14
J 0
(-3437 3433);
DISPLAY 0.489362 (-3437 3433);
PAINT GREEN (-3437 3433);
FORCEPROP 2 LAST CDS_LIB mstr_standard
J 0
(-3375 3425);
DISPLAY 0.723404 (-3375 3425);
PAINT MONO (-3375 3425);
DISPLAY INVISIBLE (-3375 3425);
FORCEPROP 1 LAST BODY_TYPE PLUMBING
J 0
(-3375 3475);
DISPLAY 0.872340 (-3375 3475);
PAINT GREEN (-3375 3475);
DISPLAY INVISIBLE (-3375 3475);
FORCEPROP 1 LAST HDL_TAP TRUE
J 0
(-3050 3300);
DISPLAY 0.872340 (-3050 3300);
DISPLAY INVISIBLE (-3050 3300);
FORCEPROP 1 LAST PATH I209
J 0
(-3377 3425);
DISPLAY 0.872340 (-3377 3425);
PAINT GREEN (-3377 3425);
DISPLAY INVISIBLE (-3377 3425);
FORCEADD TAP..1
(-3375 3375);
FORCEPROP 3 LASTPIN (-3425 3375) SIG_NAME M_F_CPU0_SB_DQ<15>
J 0
(-3415 3385);
DISPLAY 0.659574 (-3415 3385);
PAINT MONO (-3415 3385);
DISPLAY INVISIBLE (-3415 3385);
FORCEPROP 1 LASTPIN (-3425 3375) BN 15
J 0
(-3437 3383);
DISPLAY 0.489362 (-3437 3383);
PAINT GREEN (-3437 3383);
FORCEPROP 2 LAST CDS_LIB mstr_standard
J 0
(-3375 3375);
DISPLAY 0.723404 (-3375 3375);
PAINT MONO (-3375 3375);
DISPLAY INVISIBLE (-3375 3375);
FORCEPROP 1 LAST BODY_TYPE PLUMBING
J 0
(-3375 3425);
DISPLAY 0.872340 (-3375 3425);
PAINT GREEN (-3375 3425);
DISPLAY INVISIBLE (-3375 3425);
FORCEPROP 1 LAST HDL_TAP TRUE
J 0
(-3050 3250);
DISPLAY 0.872340 (-3050 3250);
DISPLAY INVISIBLE (-3050 3250);
FORCEPROP 1 LAST PATH I210
J 0
(-3377 3375);
DISPLAY 0.872340 (-3377 3375);
PAINT GREEN (-3377 3375);
DISPLAY INVISIBLE (-3377 3375);
FORCEADD TAP..1
(-3375 3275);
FORCEPROP 3 LASTPIN (-3425 3275) SIG_NAME M_F_CPU0_SB_DQ<16>
J 0
(-3415 3285);
DISPLAY 0.659574 (-3415 3285);
PAINT MONO (-3415 3285);
DISPLAY INVISIBLE (-3415 3285);
FORCEPROP 1 LASTPIN (-3425 3275) BN 16
J 0
(-3437 3283);
DISPLAY 0.489362 (-3437 3283);
PAINT GREEN (-3437 3283);
FORCEPROP 2 LAST CDS_LIB mstr_standard
J 0
(-3375 3275);
DISPLAY 0.723404 (-3375 3275);
PAINT MONO (-3375 3275);
DISPLAY INVISIBLE (-3375 3275);
FORCEPROP 1 LAST BODY_TYPE PLUMBING
J 0
(-3375 3325);
DISPLAY 0.872340 (-3375 3325);
PAINT GREEN (-3375 3325);
DISPLAY INVISIBLE (-3375 3325);
FORCEPROP 1 LAST HDL_TAP TRUE
J 0
(-3050 3150);
DISPLAY 0.872340 (-3050 3150);
DISPLAY INVISIBLE (-3050 3150);
FORCEPROP 1 LAST PATH I211
J 0
(-3377 3275);
DISPLAY 0.872340 (-3377 3275);
PAINT GREEN (-3377 3275);
DISPLAY INVISIBLE (-3377 3275);
FORCEADD TAP..1
(-3375 3225);
FORCEPROP 3 LASTPIN (-3425 3225) SIG_NAME M_F_CPU0_SB_DQ<17>
J 0
(-3415 3235);
DISPLAY 0.659574 (-3415 3235);
PAINT MONO (-3415 3235);
DISPLAY INVISIBLE (-3415 3235);
FORCEPROP 1 LASTPIN (-3425 3225) BN 17
J 0
(-3437 3233);
DISPLAY 0.489362 (-3437 3233);
PAINT GREEN (-3437 3233);
FORCEPROP 2 LAST CDS_LIB mstr_standard
J 0
(-3375 3225);
DISPLAY 0.723404 (-3375 3225);
PAINT MONO (-3375 3225);
DISPLAY INVISIBLE (-3375 3225);
FORCEPROP 1 LAST BODY_TYPE PLUMBING
J 0
(-3375 3275);
DISPLAY 0.872340 (-3375 3275);
PAINT GREEN (-3375 3275);
DISPLAY INVISIBLE (-3375 3275);
FORCEPROP 1 LAST HDL_TAP TRUE
J 0
(-3050 3100);
DISPLAY 0.872340 (-3050 3100);
DISPLAY INVISIBLE (-3050 3100);
FORCEPROP 1 LAST PATH I212
J 0
(-3377 3225);
DISPLAY 0.872340 (-3377 3225);
PAINT GREEN (-3377 3225);
DISPLAY INVISIBLE (-3377 3225);
FORCEADD TAP..1
(-3375 3075);
FORCEPROP 3 LASTPIN (-3425 3075) SIG_NAME M_F_CPU0_SB_DQ<20>
J 0
(-3415 3085);
DISPLAY 0.659574 (-3415 3085);
PAINT MONO (-3415 3085);
DISPLAY INVISIBLE (-3415 3085);
FORCEPROP 1 LASTPIN (-3425 3075) BN 20
J 0
(-3437 3083);
DISPLAY 0.489362 (-3437 3083);
PAINT GREEN (-3437 3083);
FORCEPROP 2 LAST CDS_LIB mstr_standard
J 0
(-3375 3075);
DISPLAY 0.723404 (-3375 3075);
PAINT MONO (-3375 3075);
DISPLAY INVISIBLE (-3375 3075);
FORCEPROP 1 LAST BODY_TYPE PLUMBING
J 0
(-3375 3125);
DISPLAY 0.872340 (-3375 3125);
PAINT GREEN (-3375 3125);
DISPLAY INVISIBLE (-3375 3125);
FORCEPROP 1 LAST HDL_TAP TRUE
J 0
(-3050 2950);
DISPLAY 0.872340 (-3050 2950);
DISPLAY INVISIBLE (-3050 2950);
FORCEPROP 1 LAST PATH I213
J 0
(-3377 3075);
DISPLAY 0.872340 (-3377 3075);
PAINT GREEN (-3377 3075);
DISPLAY INVISIBLE (-3377 3075);
FORCEADD TAP..1
(-3375 3125);
FORCEPROP 3 LASTPIN (-3425 3125) SIG_NAME M_F_CPU0_SB_DQ<19>
J 0
(-3415 3135);
DISPLAY 0.659574 (-3415 3135);
PAINT MONO (-3415 3135);
DISPLAY INVISIBLE (-3415 3135);
FORCEPROP 1 LASTPIN (-3425 3125) BN 19
J 0
(-3437 3133);
DISPLAY 0.489362 (-3437 3133);
PAINT GREEN (-3437 3133);
FORCEPROP 2 LAST CDS_LIB mstr_standard
J 0
(-3375 3125);
DISPLAY 0.723404 (-3375 3125);
PAINT MONO (-3375 3125);
DISPLAY INVISIBLE (-3375 3125);
FORCEPROP 1 LAST BODY_TYPE PLUMBING
J 0
(-3375 3175);
DISPLAY 0.872340 (-3375 3175);
PAINT GREEN (-3375 3175);
DISPLAY INVISIBLE (-3375 3175);
FORCEPROP 1 LAST HDL_TAP TRUE
J 0
(-3050 3000);
DISPLAY 0.872340 (-3050 3000);
DISPLAY INVISIBLE (-3050 3000);
FORCEPROP 1 LAST PATH I214
J 0
(-3377 3125);
DISPLAY 0.872340 (-3377 3125);
PAINT GREEN (-3377 3125);
DISPLAY INVISIBLE (-3377 3125);
FORCEADD TAP..1
(-3375 3175);
FORCEPROP 3 LASTPIN (-3425 3175) SIG_NAME M_F_CPU0_SB_DQ<18>
J 0
(-3415 3185);
DISPLAY 0.659574 (-3415 3185);
PAINT MONO (-3415 3185);
DISPLAY INVISIBLE (-3415 3185);
FORCEPROP 1 LASTPIN (-3425 3175) BN 18
J 0
(-3437 3183);
DISPLAY 0.489362 (-3437 3183);
PAINT GREEN (-3437 3183);
FORCEPROP 2 LAST CDS_LIB mstr_standard
J 0
(-3375 3175);
DISPLAY 0.723404 (-3375 3175);
PAINT MONO (-3375 3175);
DISPLAY INVISIBLE (-3375 3175);
FORCEPROP 1 LAST BODY_TYPE PLUMBING
J 0
(-3375 3225);
DISPLAY 0.872340 (-3375 3225);
PAINT GREEN (-3375 3225);
DISPLAY INVISIBLE (-3375 3225);
FORCEPROP 1 LAST HDL_TAP TRUE
J 0
(-3050 3050);
DISPLAY 0.872340 (-3050 3050);
DISPLAY INVISIBLE (-3050 3050);
FORCEPROP 1 LAST PATH I215
J 0
(-3377 3175);
DISPLAY 0.872340 (-3377 3175);
PAINT GREEN (-3377 3175);
DISPLAY INVISIBLE (-3377 3175);
FORCEADD TAP..1
(-3375 2975);
FORCEPROP 3 LASTPIN (-3425 2975) SIG_NAME M_F_CPU0_SB_DQ<22>
J 0
(-3415 2985);
DISPLAY 0.659574 (-3415 2985);
PAINT MONO (-3415 2985);
DISPLAY INVISIBLE (-3415 2985);
FORCEPROP 1 LASTPIN (-3425 2975) BN 22
J 0
(-3437 2983);
DISPLAY 0.489362 (-3437 2983);
PAINT GREEN (-3437 2983);
FORCEPROP 2 LAST CDS_LIB mstr_standard
J 0
(-3375 2975);
DISPLAY 0.723404 (-3375 2975);
PAINT MONO (-3375 2975);
DISPLAY INVISIBLE (-3375 2975);
FORCEPROP 1 LAST BODY_TYPE PLUMBING
J 0
(-3375 3025);
DISPLAY 0.872340 (-3375 3025);
PAINT GREEN (-3375 3025);
DISPLAY INVISIBLE (-3375 3025);
FORCEPROP 1 LAST HDL_TAP TRUE
J 0
(-3050 2850);
DISPLAY 0.872340 (-3050 2850);
DISPLAY INVISIBLE (-3050 2850);
FORCEPROP 1 LAST PATH I216
J 0
(-3377 2975);
DISPLAY 0.872340 (-3377 2975);
PAINT GREEN (-3377 2975);
DISPLAY INVISIBLE (-3377 2975);
FORCEADD TAP..1
(-3375 3025);
FORCEPROP 3 LASTPIN (-3425 3025) SIG_NAME M_F_CPU0_SB_DQ<21>
J 0
(-3415 3035);
DISPLAY 0.659574 (-3415 3035);
PAINT MONO (-3415 3035);
DISPLAY INVISIBLE (-3415 3035);
FORCEPROP 1 LASTPIN (-3425 3025) BN 21
J 0
(-3437 3033);
DISPLAY 0.489362 (-3437 3033);
PAINT GREEN (-3437 3033);
FORCEPROP 2 LAST CDS_LIB mstr_standard
J 0
(-3375 3025);
DISPLAY 0.723404 (-3375 3025);
PAINT MONO (-3375 3025);
DISPLAY INVISIBLE (-3375 3025);
FORCEPROP 1 LAST BODY_TYPE PLUMBING
J 0
(-3375 3075);
DISPLAY 0.872340 (-3375 3075);
PAINT GREEN (-3375 3075);
DISPLAY INVISIBLE (-3375 3075);
FORCEPROP 1 LAST HDL_TAP TRUE
J 0
(-3050 2900);
DISPLAY 0.872340 (-3050 2900);
DISPLAY INVISIBLE (-3050 2900);
FORCEPROP 1 LAST PATH I217
J 0
(-3377 3025);
DISPLAY 0.872340 (-3377 3025);
PAINT GREEN (-3377 3025);
DISPLAY INVISIBLE (-3377 3025);
FORCEADD TAP..1
(-3375 2825);
FORCEPROP 3 LASTPIN (-3425 2825) SIG_NAME M_F_CPU0_SB_DQ<24>
J 0
(-3415 2835);
DISPLAY 0.659574 (-3415 2835);
PAINT MONO (-3415 2835);
DISPLAY INVISIBLE (-3415 2835);
FORCEPROP 1 LASTPIN (-3425 2825) BN 24
J 0
(-3437 2833);
DISPLAY 0.489362 (-3437 2833);
PAINT GREEN (-3437 2833);
FORCEPROP 2 LAST CDS_LIB mstr_standard
J 0
(-3375 2825);
DISPLAY 0.723404 (-3375 2825);
PAINT MONO (-3375 2825);
DISPLAY INVISIBLE (-3375 2825);
FORCEPROP 1 LAST BODY_TYPE PLUMBING
J 0
(-3375 2875);
DISPLAY 0.872340 (-3375 2875);
PAINT GREEN (-3375 2875);
DISPLAY INVISIBLE (-3375 2875);
FORCEPROP 1 LAST HDL_TAP TRUE
J 0
(-3050 2700);
DISPLAY 0.872340 (-3050 2700);
DISPLAY INVISIBLE (-3050 2700);
FORCEPROP 1 LAST PATH I218
J 0
(-3377 2825);
DISPLAY 0.872340 (-3377 2825);
PAINT GREEN (-3377 2825);
DISPLAY INVISIBLE (-3377 2825);
FORCEADD TAP..1
(-3375 2925);
FORCEPROP 3 LASTPIN (-3425 2925) SIG_NAME M_F_CPU0_SB_DQ<23>
J 0
(-3415 2935);
DISPLAY 0.659574 (-3415 2935);
PAINT MONO (-3415 2935);
DISPLAY INVISIBLE (-3415 2935);
FORCEPROP 1 LASTPIN (-3425 2925) BN 23
J 0
(-3437 2933);
DISPLAY 0.489362 (-3437 2933);
PAINT GREEN (-3437 2933);
FORCEPROP 2 LAST CDS_LIB mstr_standard
J 0
(-3375 2925);
DISPLAY 0.723404 (-3375 2925);
PAINT MONO (-3375 2925);
DISPLAY INVISIBLE (-3375 2925);
FORCEPROP 1 LAST BODY_TYPE PLUMBING
J 0
(-3375 2975);
DISPLAY 0.872340 (-3375 2975);
PAINT GREEN (-3375 2975);
DISPLAY INVISIBLE (-3375 2975);
FORCEPROP 1 LAST HDL_TAP TRUE
J 0
(-3050 2800);
DISPLAY 0.872340 (-3050 2800);
DISPLAY INVISIBLE (-3050 2800);
FORCEPROP 1 LAST PATH I219
J 0
(-3377 2925);
DISPLAY 0.872340 (-3377 2925);
PAINT GREEN (-3377 2925);
DISPLAY INVISIBLE (-3377 2925);
FORCEADD TAP..1
(-3375 2775);
FORCEPROP 3 LASTPIN (-3425 2775) SIG_NAME M_F_CPU0_SB_DQ<25>
J 0
(-3415 2785);
DISPLAY 0.659574 (-3415 2785);
PAINT MONO (-3415 2785);
DISPLAY INVISIBLE (-3415 2785);
FORCEPROP 1 LASTPIN (-3425 2775) BN 25
J 0
(-3437 2783);
DISPLAY 0.489362 (-3437 2783);
PAINT GREEN (-3437 2783);
FORCEPROP 2 LAST CDS_LIB mstr_standard
J 0
(-3375 2775);
DISPLAY 0.723404 (-3375 2775);
PAINT MONO (-3375 2775);
DISPLAY INVISIBLE (-3375 2775);
FORCEPROP 1 LAST BODY_TYPE PLUMBING
J 0
(-3375 2825);
DISPLAY 0.872340 (-3375 2825);
PAINT GREEN (-3375 2825);
DISPLAY INVISIBLE (-3375 2825);
FORCEPROP 1 LAST HDL_TAP TRUE
J 0
(-3050 2650);
DISPLAY 0.872340 (-3050 2650);
DISPLAY INVISIBLE (-3050 2650);
FORCEPROP 1 LAST PATH I220
J 0
(-3377 2775);
DISPLAY 0.872340 (-3377 2775);
PAINT GREEN (-3377 2775);
DISPLAY INVISIBLE (-3377 2775);
FORCEADD TAP..1
(-3375 2725);
FORCEPROP 3 LASTPIN (-3425 2725) SIG_NAME M_F_CPU0_SB_DQ<26>
J 0
(-3415 2735);
DISPLAY 0.659574 (-3415 2735);
PAINT MONO (-3415 2735);
DISPLAY INVISIBLE (-3415 2735);
FORCEPROP 1 LASTPIN (-3425 2725) BN 26
J 0
(-3437 2733);
DISPLAY 0.489362 (-3437 2733);
PAINT GREEN (-3437 2733);
FORCEPROP 2 LAST CDS_LIB mstr_standard
J 0
(-3375 2725);
DISPLAY 0.723404 (-3375 2725);
PAINT MONO (-3375 2725);
DISPLAY INVISIBLE (-3375 2725);
FORCEPROP 1 LAST BODY_TYPE PLUMBING
J 0
(-3375 2775);
DISPLAY 0.872340 (-3375 2775);
PAINT GREEN (-3375 2775);
DISPLAY INVISIBLE (-3375 2775);
FORCEPROP 1 LAST HDL_TAP TRUE
J 0
(-3050 2600);
DISPLAY 0.872340 (-3050 2600);
DISPLAY INVISIBLE (-3050 2600);
FORCEPROP 1 LAST PATH I221
J 0
(-3377 2725);
DISPLAY 0.872340 (-3377 2725);
PAINT GREEN (-3377 2725);
DISPLAY INVISIBLE (-3377 2725);
FORCEADD TAP..1
(-3375 2575);
FORCEPROP 3 LASTPIN (-3425 2575) SIG_NAME M_F_CPU0_SB_DQ<29>
J 0
(-3415 2585);
DISPLAY 0.659574 (-3415 2585);
PAINT MONO (-3415 2585);
DISPLAY INVISIBLE (-3415 2585);
FORCEPROP 1 LASTPIN (-3425 2575) BN 29
J 0
(-3437 2583);
DISPLAY 0.489362 (-3437 2583);
PAINT GREEN (-3437 2583);
FORCEPROP 2 LAST CDS_LIB mstr_standard
J 0
(-3375 2575);
DISPLAY 0.723404 (-3375 2575);
PAINT MONO (-3375 2575);
DISPLAY INVISIBLE (-3375 2575);
FORCEPROP 1 LAST BODY_TYPE PLUMBING
J 0
(-3375 2625);
DISPLAY 0.872340 (-3375 2625);
PAINT GREEN (-3375 2625);
DISPLAY INVISIBLE (-3375 2625);
FORCEPROP 1 LAST HDL_TAP TRUE
J 0
(-3050 2450);
DISPLAY 0.872340 (-3050 2450);
DISPLAY INVISIBLE (-3050 2450);
FORCEPROP 1 LAST PATH I222
J 0
(-3377 2575);
DISPLAY 0.872340 (-3377 2575);
PAINT GREEN (-3377 2575);
DISPLAY INVISIBLE (-3377 2575);
FORCEADD TAP..1
(-3375 2625);
FORCEPROP 3 LASTPIN (-3425 2625) SIG_NAME M_F_CPU0_SB_DQ<28>
J 0
(-3415 2635);
DISPLAY 0.659574 (-3415 2635);
PAINT MONO (-3415 2635);
DISPLAY INVISIBLE (-3415 2635);
FORCEPROP 1 LASTPIN (-3425 2625) BN 28
J 0
(-3437 2633);
DISPLAY 0.489362 (-3437 2633);
PAINT GREEN (-3437 2633);
FORCEPROP 2 LAST CDS_LIB mstr_standard
J 0
(-3375 2625);
DISPLAY 0.723404 (-3375 2625);
PAINT MONO (-3375 2625);
DISPLAY INVISIBLE (-3375 2625);
FORCEPROP 1 LAST BODY_TYPE PLUMBING
J 0
(-3375 2675);
DISPLAY 0.872340 (-3375 2675);
PAINT GREEN (-3375 2675);
DISPLAY INVISIBLE (-3375 2675);
FORCEPROP 1 LAST HDL_TAP TRUE
J 0
(-3050 2500);
DISPLAY 0.872340 (-3050 2500);
DISPLAY INVISIBLE (-3050 2500);
FORCEPROP 1 LAST PATH I223
J 0
(-3377 2625);
DISPLAY 0.872340 (-3377 2625);
PAINT GREEN (-3377 2625);
DISPLAY INVISIBLE (-3377 2625);
FORCEADD TAP..1
(-3375 2675);
FORCEPROP 3 LASTPIN (-3425 2675) SIG_NAME M_F_CPU0_SB_DQ<27>
J 0
(-3415 2685);
DISPLAY 0.659574 (-3415 2685);
PAINT MONO (-3415 2685);
DISPLAY INVISIBLE (-3415 2685);
FORCEPROP 1 LASTPIN (-3425 2675) BN 27
J 0
(-3437 2683);
DISPLAY 0.489362 (-3437 2683);
PAINT GREEN (-3437 2683);
FORCEPROP 2 LAST CDS_LIB mstr_standard
J 0
(-3375 2675);
DISPLAY 0.723404 (-3375 2675);
PAINT MONO (-3375 2675);
DISPLAY INVISIBLE (-3375 2675);
FORCEPROP 1 LAST BODY_TYPE PLUMBING
J 0
(-3375 2725);
DISPLAY 0.872340 (-3375 2725);
PAINT GREEN (-3375 2725);
DISPLAY INVISIBLE (-3375 2725);
FORCEPROP 1 LAST HDL_TAP TRUE
J 0
(-3050 2550);
DISPLAY 0.872340 (-3050 2550);
DISPLAY INVISIBLE (-3050 2550);
FORCEPROP 1 LAST PATH I224
J 0
(-3377 2675);
DISPLAY 0.872340 (-3377 2675);
PAINT GREEN (-3377 2675);
DISPLAY INVISIBLE (-3377 2675);
FORCEADD TAP..1
(-3375 2525);
FORCEPROP 3 LASTPIN (-3425 2525) SIG_NAME M_F_CPU0_SB_DQ<30>
J 0
(-3415 2535);
DISPLAY 0.659574 (-3415 2535);
PAINT MONO (-3415 2535);
DISPLAY INVISIBLE (-3415 2535);
FORCEPROP 1 LASTPIN (-3425 2525) BN 30
J 0
(-3437 2533);
DISPLAY 0.489362 (-3437 2533);
PAINT GREEN (-3437 2533);
FORCEPROP 2 LAST CDS_LIB mstr_standard
J 0
(-3375 2525);
DISPLAY 0.723404 (-3375 2525);
PAINT MONO (-3375 2525);
DISPLAY INVISIBLE (-3375 2525);
FORCEPROP 1 LAST BODY_TYPE PLUMBING
J 0
(-3375 2575);
DISPLAY 0.872340 (-3375 2575);
PAINT GREEN (-3375 2575);
DISPLAY INVISIBLE (-3375 2575);
FORCEPROP 1 LAST HDL_TAP TRUE
J 0
(-3050 2400);
DISPLAY 0.872340 (-3050 2400);
DISPLAY INVISIBLE (-3050 2400);
FORCEPROP 1 LAST PATH I225
J 0
(-3377 2525);
DISPLAY 0.872340 (-3377 2525);
PAINT GREEN (-3377 2525);
DISPLAY INVISIBLE (-3377 2525);
FORCEADD TAP..1
(-3375 2475);
FORCEPROP 3 LASTPIN (-3425 2475) SIG_NAME M_F_CPU0_SB_DQ<31>
J 0
(-3415 2485);
DISPLAY 0.659574 (-3415 2485);
PAINT MONO (-3415 2485);
DISPLAY INVISIBLE (-3415 2485);
FORCEPROP 1 LASTPIN (-3425 2475) BN 31
J 0
(-3437 2483);
DISPLAY 0.489362 (-3437 2483);
PAINT GREEN (-3437 2483);
FORCEPROP 2 LAST CDS_LIB mstr_standard
J 0
(-3375 2475);
DISPLAY 0.723404 (-3375 2475);
PAINT MONO (-3375 2475);
DISPLAY INVISIBLE (-3375 2475);
FORCEPROP 1 LAST BODY_TYPE PLUMBING
J 0
(-3375 2525);
DISPLAY 0.872340 (-3375 2525);
PAINT GREEN (-3375 2525);
DISPLAY INVISIBLE (-3375 2525);
FORCEPROP 1 LAST HDL_TAP TRUE
J 0
(-3050 2350);
DISPLAY 0.872340 (-3050 2350);
DISPLAY INVISIBLE (-3050 2350);
FORCEPROP 1 LAST PATH I226
J 0
(-3377 2475);
DISPLAY 0.872340 (-3377 2475);
PAINT GREEN (-3377 2475);
DISPLAY INVISIBLE (-3377 2475);
FORCEADD TAP..1
(-3375 2325);
FORCEPROP 3 LASTPIN (-3425 2325) SIG_NAME M_F_CPU0_SA_CB<1>
J 0
(-3415 2335);
DISPLAY 0.659574 (-3415 2335);
PAINT MONO (-3415 2335);
DISPLAY INVISIBLE (-3415 2335);
FORCEPROP 1 LASTPIN (-3425 2325) BN 1
J 0
(-3437 2333);
DISPLAY 0.489362 (-3437 2333);
PAINT GREEN (-3437 2333);
FORCEPROP 2 LAST CDS_LIB mstr_standard
J 2
(-3375 2325);
DISPLAY 0.723404 (-3375 2325);
PAINT MONO (-3375 2325);
DISPLAY INVISIBLE (-3375 2325);
FORCEPROP 1 LAST BODY_TYPE PLUMBING
J 0
(-3375 2375);
DISPLAY 0.872340 (-3375 2375);
PAINT GREEN (-3375 2375);
DISPLAY INVISIBLE (-3375 2375);
FORCEPROP 1 LAST HDL_TAP TRUE
J 0
(-3050 2200);
DISPLAY 0.872340 (-3050 2200);
DISPLAY INVISIBLE (-3050 2200);
FORCEPROP 1 LAST PATH I227
J 0
(-3377 2325);
DISPLAY 0.872340 (-3377 2325);
PAINT GREEN (-3377 2325);
DISPLAY INVISIBLE (-3377 2325);
FORCEADD TAP..1
(-3375 2375);
FORCEPROP 3 LASTPIN (-3425 2375) SIG_NAME M_F_CPU0_SA_CB<0>
J 0
(-3415 2385);
DISPLAY 0.659574 (-3415 2385);
PAINT MONO (-3415 2385);
DISPLAY INVISIBLE (-3415 2385);
FORCEPROP 1 LASTPIN (-3425 2375) BN 0
J 0
(-3437 2383);
DISPLAY 0.489362 (-3437 2383);
PAINT GREEN (-3437 2383);
FORCEPROP 2 LAST CDS_LIB mstr_standard
J 2
(-3375 2375);
DISPLAY 0.723404 (-3375 2375);
PAINT MONO (-3375 2375);
DISPLAY INVISIBLE (-3375 2375);
FORCEPROP 1 LAST BODY_TYPE PLUMBING
J 0
(-3375 2425);
DISPLAY 0.872340 (-3375 2425);
PAINT GREEN (-3375 2425);
DISPLAY INVISIBLE (-3375 2425);
FORCEPROP 1 LAST HDL_TAP TRUE
J 0
(-3050 2250);
DISPLAY 0.872340 (-3050 2250);
DISPLAY INVISIBLE (-3050 2250);
FORCEPROP 1 LAST PATH I228
J 0
(-3377 2375);
DISPLAY 0.872340 (-3377 2375);
PAINT GREEN (-3377 2375);
DISPLAY INVISIBLE (-3377 2375);
FORCEADD TAP..1
(-3375 2275);
FORCEPROP 3 LASTPIN (-3425 2275) SIG_NAME M_F_CPU0_SA_CB<2>
J 0
(-3415 2285);
DISPLAY 0.659574 (-3415 2285);
PAINT MONO (-3415 2285);
DISPLAY INVISIBLE (-3415 2285);
FORCEPROP 1 LASTPIN (-3425 2275) BN 2
J 0
(-3437 2283);
DISPLAY 0.489362 (-3437 2283);
PAINT GREEN (-3437 2283);
FORCEPROP 2 LAST CDS_LIB mstr_standard
J 2
(-3375 2275);
DISPLAY 0.723404 (-3375 2275);
PAINT MONO (-3375 2275);
DISPLAY INVISIBLE (-3375 2275);
FORCEPROP 1 LAST BODY_TYPE PLUMBING
J 0
(-3375 2325);
DISPLAY 0.872340 (-3375 2325);
PAINT GREEN (-3375 2325);
DISPLAY INVISIBLE (-3375 2325);
FORCEPROP 1 LAST HDL_TAP TRUE
J 0
(-3050 2150);
DISPLAY 0.872340 (-3050 2150);
DISPLAY INVISIBLE (-3050 2150);
FORCEPROP 1 LAST PATH I229
J 0
(-3377 2275);
DISPLAY 0.872340 (-3377 2275);
PAINT GREEN (-3377 2275);
DISPLAY INVISIBLE (-3377 2275);
FORCEADD TAP..1
(-3375 2225);
FORCEPROP 3 LASTPIN (-3425 2225) SIG_NAME M_F_CPU0_SA_CB<3>
J 0
(-3415 2235);
DISPLAY 0.659574 (-3415 2235);
PAINT MONO (-3415 2235);
DISPLAY INVISIBLE (-3415 2235);
FORCEPROP 1 LASTPIN (-3425 2225) BN 3
J 0
(-3437 2233);
DISPLAY 0.489362 (-3437 2233);
PAINT GREEN (-3437 2233);
FORCEPROP 2 LAST CDS_LIB mstr_standard
J 2
(-3375 2225);
DISPLAY 0.723404 (-3375 2225);
PAINT MONO (-3375 2225);
DISPLAY INVISIBLE (-3375 2225);
FORCEPROP 1 LAST BODY_TYPE PLUMBING
J 0
(-3375 2275);
DISPLAY 0.872340 (-3375 2275);
PAINT GREEN (-3375 2275);
DISPLAY INVISIBLE (-3375 2275);
FORCEPROP 1 LAST HDL_TAP TRUE
J 0
(-3050 2100);
DISPLAY 0.872340 (-3050 2100);
DISPLAY INVISIBLE (-3050 2100);
FORCEPROP 1 LAST PATH I230
J 0
(-3377 2225);
DISPLAY 0.872340 (-3377 2225);
PAINT GREEN (-3377 2225);
DISPLAY INVISIBLE (-3377 2225);
FORCEADD TAP..1
(-3375 2075);
FORCEPROP 3 LASTPIN (-3425 2075) SIG_NAME M_F_CPU0_SA_CB<6>
J 0
(-3415 2085);
DISPLAY 0.659574 (-3415 2085);
PAINT MONO (-3415 2085);
DISPLAY INVISIBLE (-3415 2085);
FORCEPROP 1 LASTPIN (-3425 2075) BN 6
J 0
(-3437 2083);
DISPLAY 0.489362 (-3437 2083);
PAINT GREEN (-3437 2083);
FORCEPROP 2 LAST CDS_LIB mstr_standard
J 2
(-3375 2075);
DISPLAY 0.723404 (-3375 2075);
PAINT MONO (-3375 2075);
DISPLAY INVISIBLE (-3375 2075);
FORCEPROP 1 LAST BODY_TYPE PLUMBING
J 0
(-3375 2125);
DISPLAY 0.872340 (-3375 2125);
PAINT GREEN (-3375 2125);
DISPLAY INVISIBLE (-3375 2125);
FORCEPROP 1 LAST HDL_TAP TRUE
J 0
(-3050 1950);
DISPLAY 0.872340 (-3050 1950);
DISPLAY INVISIBLE (-3050 1950);
FORCEPROP 1 LAST PATH I231
J 0
(-3377 2075);
DISPLAY 0.872340 (-3377 2075);
PAINT GREEN (-3377 2075);
DISPLAY INVISIBLE (-3377 2075);
FORCEADD TAP..1
(-3375 2125);
FORCEPROP 3 LASTPIN (-3425 2125) SIG_NAME M_F_CPU0_SA_CB<5>
J 0
(-3415 2135);
DISPLAY 0.659574 (-3415 2135);
PAINT MONO (-3415 2135);
DISPLAY INVISIBLE (-3415 2135);
FORCEPROP 1 LASTPIN (-3425 2125) BN 5
J 0
(-3437 2133);
DISPLAY 0.489362 (-3437 2133);
PAINT GREEN (-3437 2133);
FORCEPROP 2 LAST CDS_LIB mstr_standard
J 2
(-3375 2125);
DISPLAY 0.723404 (-3375 2125);
PAINT MONO (-3375 2125);
DISPLAY INVISIBLE (-3375 2125);
FORCEPROP 1 LAST BODY_TYPE PLUMBING
J 0
(-3375 2175);
DISPLAY 0.872340 (-3375 2175);
PAINT GREEN (-3375 2175);
DISPLAY INVISIBLE (-3375 2175);
FORCEPROP 1 LAST HDL_TAP TRUE
J 0
(-3050 2000);
DISPLAY 0.872340 (-3050 2000);
DISPLAY INVISIBLE (-3050 2000);
FORCEPROP 1 LAST PATH I232
J 0
(-3377 2125);
DISPLAY 0.872340 (-3377 2125);
PAINT GREEN (-3377 2125);
DISPLAY INVISIBLE (-3377 2125);
FORCEADD TAP..1
(-3375 2175);
FORCEPROP 3 LASTPIN (-3425 2175) SIG_NAME M_F_CPU0_SA_CB<4>
J 0
(-3415 2185);
DISPLAY 0.659574 (-3415 2185);
PAINT MONO (-3415 2185);
DISPLAY INVISIBLE (-3415 2185);
FORCEPROP 1 LASTPIN (-3425 2175) BN 4
J 0
(-3437 2183);
DISPLAY 0.489362 (-3437 2183);
PAINT GREEN (-3437 2183);
FORCEPROP 2 LAST CDS_LIB mstr_standard
J 2
(-3375 2175);
DISPLAY 0.723404 (-3375 2175);
PAINT MONO (-3375 2175);
DISPLAY INVISIBLE (-3375 2175);
FORCEPROP 1 LAST BODY_TYPE PLUMBING
J 0
(-3375 2225);
DISPLAY 0.872340 (-3375 2225);
PAINT GREEN (-3375 2225);
DISPLAY INVISIBLE (-3375 2225);
FORCEPROP 1 LAST HDL_TAP TRUE
J 0
(-3050 2050);
DISPLAY 0.872340 (-3050 2050);
DISPLAY INVISIBLE (-3050 2050);
FORCEPROP 1 LAST PATH I233
J 0
(-3377 2175);
DISPLAY 0.872340 (-3377 2175);
PAINT GREEN (-3377 2175);
DISPLAY INVISIBLE (-3377 2175);
FORCEADD OFFPAGE..6
R 2
(-2775 1975);
FORCEPROP 2 LAST $XR0 90 
J 0
(-2561 1975);
DISPLAY 0.638298 (-2561 1975);
PAINT MONO (-2561 1975);
FORCEPROP 2 LAST PATH I234
J 0
(-2550 2025);
DISPLAY 1.021277 (-2550 2025);
DISPLAY INVISIBLE (-2550 2025);
FORCEPROP 1 LAST COMMENT_BODY TRUE
J 2
(-2875 1900);
DISPLAY 0.872340 (-2875 1900);
PAINT GREEN (-2875 1900);
DISPLAY INVISIBLE (-2875 1900);
FORCEPROP 1 LAST OFFPAGE TRUE
J 2
(-3100 1850);
DISPLAY 0.872340 (-3100 1850);
PAINT GREEN (-3100 1850);
DISPLAY INVISIBLE (-3100 1850);
FORCEPROP 2 LAST CDS_LIB mstr_standard
J 2
(-2775 1975);
DISPLAY 0.723404 (-2775 1975);
PAINT MONO (-2775 1975);
DISPLAY INVISIBLE (-2775 1975);
FORCEADD TAP..1
(-3375 2025);
FORCEPROP 3 LASTPIN (-3425 2025) SIG_NAME M_F_CPU0_SA_CB<7>
J 0
(-3415 2035);
DISPLAY 0.659574 (-3415 2035);
PAINT MONO (-3415 2035);
DISPLAY INVISIBLE (-3415 2035);
FORCEPROP 1 LASTPIN (-3425 2025) BN 7
J 0
(-3437 2033);
DISPLAY 0.489362 (-3437 2033);
PAINT GREEN (-3437 2033);
FORCEPROP 2 LAST CDS_LIB mstr_standard
J 2
(-3375 2025);
DISPLAY 0.723404 (-3375 2025);
PAINT MONO (-3375 2025);
DISPLAY INVISIBLE (-3375 2025);
FORCEPROP 1 LAST BODY_TYPE PLUMBING
J 0
(-3375 2075);
DISPLAY 0.872340 (-3375 2075);
PAINT GREEN (-3375 2075);
DISPLAY INVISIBLE (-3375 2075);
FORCEPROP 1 LAST HDL_TAP TRUE
J 0
(-3050 1900);
DISPLAY 0.872340 (-3050 1900);
DISPLAY INVISIBLE (-3050 1900);
FORCEPROP 1 LAST PATH I235
J 0
(-3377 2025);
DISPLAY 0.872340 (-3377 2025);
PAINT GREEN (-3377 2025);
DISPLAY INVISIBLE (-3377 2025);
FORCEADD TAP..1
(-3375 1925);
FORCEPROP 3 LASTPIN (-3425 1925) SIG_NAME M_F_CPU0_SB_CB<0>
J 0
(-3415 1935);
DISPLAY 0.659574 (-3415 1935);
PAINT MONO (-3415 1935);
DISPLAY INVISIBLE (-3415 1935);
FORCEPROP 1 LASTPIN (-3425 1925) BN 0
J 0
(-3437 1933);
DISPLAY 0.489362 (-3437 1933);
PAINT GREEN (-3437 1933);
FORCEPROP 2 LAST CDS_LIB mstr_standard
J 2
(-3375 1925);
DISPLAY 0.723404 (-3375 1925);
PAINT MONO (-3375 1925);
DISPLAY INVISIBLE (-3375 1925);
FORCEPROP 1 LAST BODY_TYPE PLUMBING
J 0
(-3375 1975);
DISPLAY 0.872340 (-3375 1975);
PAINT GREEN (-3375 1975);
DISPLAY INVISIBLE (-3375 1975);
FORCEPROP 1 LAST HDL_TAP TRUE
J 0
(-3050 1800);
DISPLAY 0.872340 (-3050 1800);
DISPLAY INVISIBLE (-3050 1800);
FORCEPROP 1 LAST PATH I236
J 0
(-3377 1925);
DISPLAY 0.872340 (-3377 1925);
PAINT GREEN (-3377 1925);
DISPLAY INVISIBLE (-3377 1925);
FORCEADD TAP..1
(-3375 1825);
FORCEPROP 3 LASTPIN (-3425 1825) SIG_NAME M_F_CPU0_SB_CB<2>
J 0
(-3415 1835);
DISPLAY 0.659574 (-3415 1835);
PAINT MONO (-3415 1835);
DISPLAY INVISIBLE (-3415 1835);
FORCEPROP 1 LASTPIN (-3425 1825) BN 2
J 0
(-3437 1833);
DISPLAY 0.489362 (-3437 1833);
PAINT GREEN (-3437 1833);
FORCEPROP 2 LAST CDS_LIB mstr_standard
J 2
(-3375 1825);
DISPLAY 0.723404 (-3375 1825);
PAINT MONO (-3375 1825);
DISPLAY INVISIBLE (-3375 1825);
FORCEPROP 1 LAST BODY_TYPE PLUMBING
J 0
(-3375 1875);
DISPLAY 0.872340 (-3375 1875);
PAINT GREEN (-3375 1875);
DISPLAY INVISIBLE (-3375 1875);
FORCEPROP 1 LAST HDL_TAP TRUE
J 0
(-3050 1700);
DISPLAY 0.872340 (-3050 1700);
DISPLAY INVISIBLE (-3050 1700);
FORCEPROP 1 LAST PATH I237
J 0
(-3377 1825);
DISPLAY 0.872340 (-3377 1825);
PAINT GREEN (-3377 1825);
DISPLAY INVISIBLE (-3377 1825);
FORCEADD TAP..1
(-3375 1875);
FORCEPROP 3 LASTPIN (-3425 1875) SIG_NAME M_F_CPU0_SB_CB<1>
J 0
(-3415 1885);
DISPLAY 0.659574 (-3415 1885);
PAINT MONO (-3415 1885);
DISPLAY INVISIBLE (-3415 1885);
FORCEPROP 1 LASTPIN (-3425 1875) BN 1
J 0
(-3437 1883);
DISPLAY 0.489362 (-3437 1883);
PAINT GREEN (-3437 1883);
FORCEPROP 2 LAST CDS_LIB mstr_standard
J 2
(-3375 1875);
DISPLAY 0.723404 (-3375 1875);
PAINT MONO (-3375 1875);
DISPLAY INVISIBLE (-3375 1875);
FORCEPROP 1 LAST BODY_TYPE PLUMBING
J 0
(-3375 1925);
DISPLAY 0.872340 (-3375 1925);
PAINT GREEN (-3375 1925);
DISPLAY INVISIBLE (-3375 1925);
FORCEPROP 1 LAST HDL_TAP TRUE
J 0
(-3050 1750);
DISPLAY 0.872340 (-3050 1750);
DISPLAY INVISIBLE (-3050 1750);
FORCEPROP 1 LAST PATH I238
J 0
(-3377 1875);
DISPLAY 0.872340 (-3377 1875);
PAINT GREEN (-3377 1875);
DISPLAY INVISIBLE (-3377 1875);
FORCEADD TAP..1
(-3375 1675);
FORCEPROP 3 LASTPIN (-3425 1675) SIG_NAME M_F_CPU0_SB_CB<5>
J 0
(-3415 1685);
DISPLAY 0.659574 (-3415 1685);
PAINT MONO (-3415 1685);
DISPLAY INVISIBLE (-3415 1685);
FORCEPROP 1 LASTPIN (-3425 1675) BN 5
J 0
(-3437 1683);
DISPLAY 0.489362 (-3437 1683);
PAINT GREEN (-3437 1683);
FORCEPROP 2 LAST CDS_LIB mstr_standard
J 2
(-3375 1675);
DISPLAY 0.723404 (-3375 1675);
PAINT MONO (-3375 1675);
DISPLAY INVISIBLE (-3375 1675);
FORCEPROP 1 LAST BODY_TYPE PLUMBING
J 0
(-3375 1725);
DISPLAY 0.872340 (-3375 1725);
PAINT GREEN (-3375 1725);
DISPLAY INVISIBLE (-3375 1725);
FORCEPROP 1 LAST HDL_TAP TRUE
J 0
(-3050 1550);
DISPLAY 0.872340 (-3050 1550);
DISPLAY INVISIBLE (-3050 1550);
FORCEPROP 1 LAST PATH I239
J 0
(-3377 1675);
DISPLAY 0.872340 (-3377 1675);
PAINT GREEN (-3377 1675);
DISPLAY INVISIBLE (-3377 1675);
FORCEADD TAP..1
(-3375 1725);
FORCEPROP 3 LASTPIN (-3425 1725) SIG_NAME M_F_CPU0_SB_CB<4>
J 0
(-3415 1735);
DISPLAY 0.659574 (-3415 1735);
PAINT MONO (-3415 1735);
DISPLAY INVISIBLE (-3415 1735);
FORCEPROP 1 LASTPIN (-3425 1725) BN 4
J 0
(-3437 1733);
DISPLAY 0.489362 (-3437 1733);
PAINT GREEN (-3437 1733);
FORCEPROP 2 LAST CDS_LIB mstr_standard
J 2
(-3375 1725);
DISPLAY 0.723404 (-3375 1725);
PAINT MONO (-3375 1725);
DISPLAY INVISIBLE (-3375 1725);
FORCEPROP 1 LAST BODY_TYPE PLUMBING
J 0
(-3375 1775);
DISPLAY 0.872340 (-3375 1775);
PAINT GREEN (-3375 1775);
DISPLAY INVISIBLE (-3375 1775);
FORCEPROP 1 LAST HDL_TAP TRUE
J 0
(-3050 1600);
DISPLAY 0.872340 (-3050 1600);
DISPLAY INVISIBLE (-3050 1600);
FORCEPROP 1 LAST PATH I240
J 0
(-3377 1725);
DISPLAY 0.872340 (-3377 1725);
PAINT GREEN (-3377 1725);
DISPLAY INVISIBLE (-3377 1725);
FORCEADD TAP..1
(-3375 1775);
FORCEPROP 3 LASTPIN (-3425 1775) SIG_NAME M_F_CPU0_SB_CB<3>
J 0
(-3415 1785);
DISPLAY 0.659574 (-3415 1785);
PAINT MONO (-3415 1785);
DISPLAY INVISIBLE (-3415 1785);
FORCEPROP 1 LASTPIN (-3425 1775) BN 3
J 0
(-3437 1783);
DISPLAY 0.489362 (-3437 1783);
PAINT GREEN (-3437 1783);
FORCEPROP 2 LAST CDS_LIB mstr_standard
J 2
(-3375 1775);
DISPLAY 0.723404 (-3375 1775);
PAINT MONO (-3375 1775);
DISPLAY INVISIBLE (-3375 1775);
FORCEPROP 1 LAST BODY_TYPE PLUMBING
J 0
(-3375 1825);
DISPLAY 0.872340 (-3375 1825);
PAINT GREEN (-3375 1825);
DISPLAY INVISIBLE (-3375 1825);
FORCEPROP 1 LAST HDL_TAP TRUE
J 0
(-3050 1650);
DISPLAY 0.872340 (-3050 1650);
DISPLAY INVISIBLE (-3050 1650);
FORCEPROP 1 LAST PATH I241
J 0
(-3377 1775);
DISPLAY 0.872340 (-3377 1775);
PAINT GREEN (-3377 1775);
DISPLAY INVISIBLE (-3377 1775);
FORCEADD TAP..1
(-3375 1575);
FORCEPROP 3 LASTPIN (-3425 1575) SIG_NAME M_F_CPU0_SB_CB<7>
J 0
(-3415 1585);
DISPLAY 0.659574 (-3415 1585);
PAINT MONO (-3415 1585);
DISPLAY INVISIBLE (-3415 1585);
FORCEPROP 1 LASTPIN (-3425 1575) BN 7
J 0
(-3437 1583);
DISPLAY 0.489362 (-3437 1583);
PAINT GREEN (-3437 1583);
FORCEPROP 2 LAST CDS_LIB mstr_standard
J 2
(-3375 1575);
DISPLAY 0.723404 (-3375 1575);
PAINT MONO (-3375 1575);
DISPLAY INVISIBLE (-3375 1575);
FORCEPROP 1 LAST BODY_TYPE PLUMBING
J 0
(-3375 1625);
DISPLAY 0.872340 (-3375 1625);
PAINT GREEN (-3375 1625);
DISPLAY INVISIBLE (-3375 1625);
FORCEPROP 1 LAST HDL_TAP TRUE
J 0
(-3050 1450);
DISPLAY 0.872340 (-3050 1450);
DISPLAY INVISIBLE (-3050 1450);
FORCEPROP 1 LAST PATH I242
J 0
(-3377 1575);
DISPLAY 0.872340 (-3377 1575);
PAINT GREEN (-3377 1575);
DISPLAY INVISIBLE (-3377 1575);
FORCEADD TAP..1
(-3375 1625);
FORCEPROP 3 LASTPIN (-3425 1625) SIG_NAME M_F_CPU0_SB_CB<6>
J 0
(-3415 1635);
DISPLAY 0.659574 (-3415 1635);
PAINT MONO (-3415 1635);
DISPLAY INVISIBLE (-3415 1635);
FORCEPROP 1 LASTPIN (-3425 1625) BN 6
J 0
(-3437 1633);
DISPLAY 0.489362 (-3437 1633);
PAINT GREEN (-3437 1633);
FORCEPROP 2 LAST CDS_LIB mstr_standard
J 2
(-3375 1625);
DISPLAY 0.723404 (-3375 1625);
PAINT MONO (-3375 1625);
DISPLAY INVISIBLE (-3375 1625);
FORCEPROP 1 LAST BODY_TYPE PLUMBING
J 0
(-3375 1675);
DISPLAY 0.872340 (-3375 1675);
PAINT GREEN (-3375 1675);
DISPLAY INVISIBLE (-3375 1675);
FORCEPROP 1 LAST HDL_TAP TRUE
J 0
(-3050 1500);
DISPLAY 0.872340 (-3050 1500);
DISPLAY INVISIBLE (-3050 1500);
FORCEPROP 1 LAST PATH I243
J 0
(-3377 1625);
DISPLAY 0.872340 (-3377 1625);
PAINT GREEN (-3377 1625);
DISPLAY INVISIBLE (-3377 1625);
FORCEADD TAP..1
R 2
(-5800 5975);
FORCEPROP 3 LASTPIN (-5750 5975) SIG_NAME M_F_CPU0_SA_DQS_DP<0>
J 0
(-5740 5985);
DISPLAY 0.659574 (-5740 5985);
PAINT MONO (-5740 5985);
DISPLAY INVISIBLE (-5740 5985);
FORCEPROP 1 LASTPIN (-5750 5975) BN 0
J 2
(-5738 5983);
DISPLAY 0.489362 (-5738 5983);
PAINT GREEN (-5738 5983);
FORCEPROP 2 LAST CDS_LIB mstr_standard
J 2
(-5800 5975);
DISPLAY 0.723404 (-5800 5975);
PAINT MONO (-5800 5975);
DISPLAY INVISIBLE (-5800 5975);
FORCEPROP 1 LAST BODY_TYPE PLUMBING
J 2
(-5800 6025);
DISPLAY 0.872340 (-5800 6025);
PAINT GREEN (-5800 6025);
DISPLAY INVISIBLE (-5800 6025);
FORCEPROP 1 LAST HDL_TAP TRUE
J 2
(-6125 5850);
DISPLAY 0.872340 (-6125 5850);
DISPLAY INVISIBLE (-6125 5850);
FORCEPROP 1 LAST PATH I244
J 2
(-5798 5975);
DISPLAY 0.872340 (-5798 5975);
PAINT GREEN (-5798 5975);
DISPLAY INVISIBLE (-5798 5975);
FORCEADD TAP..1
R 2
(-5800 5875);
FORCEPROP 3 LASTPIN (-5750 5875) SIG_NAME M_F_CPU0_SA_DQS_DP<1>
J 0
(-5740 5885);
DISPLAY 0.659574 (-5740 5885);
PAINT MONO (-5740 5885);
DISPLAY INVISIBLE (-5740 5885);
FORCEPROP 1 LASTPIN (-5750 5875) BN 1
J 2
(-5738 5883);
DISPLAY 0.489362 (-5738 5883);
PAINT GREEN (-5738 5883);
FORCEPROP 2 LAST CDS_LIB mstr_standard
J 2
(-5800 5875);
DISPLAY 0.723404 (-5800 5875);
PAINT MONO (-5800 5875);
DISPLAY INVISIBLE (-5800 5875);
FORCEPROP 1 LAST BODY_TYPE PLUMBING
J 2
(-5800 5925);
DISPLAY 0.872340 (-5800 5925);
PAINT GREEN (-5800 5925);
DISPLAY INVISIBLE (-5800 5925);
FORCEPROP 1 LAST HDL_TAP TRUE
J 2
(-6125 5750);
DISPLAY 0.872340 (-6125 5750);
DISPLAY INVISIBLE (-6125 5750);
FORCEPROP 1 LAST PATH I245
J 2
(-5798 5875);
DISPLAY 0.872340 (-5798 5875);
PAINT GREEN (-5798 5875);
DISPLAY INVISIBLE (-5798 5875);
FORCEADD TAP..1
R 2
(-5800 5775);
FORCEPROP 3 LASTPIN (-5750 5775) SIG_NAME M_F_CPU0_SA_DQS_DP<2>
J 0
(-5740 5785);
DISPLAY 0.659574 (-5740 5785);
PAINT MONO (-5740 5785);
DISPLAY INVISIBLE (-5740 5785);
FORCEPROP 1 LASTPIN (-5750 5775) BN 2
J 2
(-5738 5783);
DISPLAY 0.489362 (-5738 5783);
PAINT GREEN (-5738 5783);
FORCEPROP 2 LAST CDS_LIB mstr_standard
J 2
(-5800 5775);
DISPLAY 0.723404 (-5800 5775);
PAINT MONO (-5800 5775);
DISPLAY INVISIBLE (-5800 5775);
FORCEPROP 1 LAST BODY_TYPE PLUMBING
J 2
(-5800 5825);
DISPLAY 0.872340 (-5800 5825);
PAINT GREEN (-5800 5825);
DISPLAY INVISIBLE (-5800 5825);
FORCEPROP 1 LAST HDL_TAP TRUE
J 2
(-6125 5650);
DISPLAY 0.872340 (-6125 5650);
DISPLAY INVISIBLE (-6125 5650);
FORCEPROP 1 LAST PATH I246
J 2
(-5798 5775);
DISPLAY 0.872340 (-5798 5775);
PAINT GREEN (-5798 5775);
DISPLAY INVISIBLE (-5798 5775);
FORCEADD TAP..1
R 2
(-5800 5675);
FORCEPROP 3 LASTPIN (-5750 5675) SIG_NAME M_F_CPU0_SA_DQS_DP<3>
J 0
(-5740 5685);
DISPLAY 0.659574 (-5740 5685);
PAINT MONO (-5740 5685);
DISPLAY INVISIBLE (-5740 5685);
FORCEPROP 1 LASTPIN (-5750 5675) BN 3
J 2
(-5738 5683);
DISPLAY 0.489362 (-5738 5683);
PAINT GREEN (-5738 5683);
FORCEPROP 2 LAST CDS_LIB mstr_standard
J 2
(-5800 5675);
DISPLAY 0.723404 (-5800 5675);
PAINT MONO (-5800 5675);
DISPLAY INVISIBLE (-5800 5675);
FORCEPROP 1 LAST BODY_TYPE PLUMBING
J 2
(-5800 5725);
DISPLAY 0.872340 (-5800 5725);
PAINT GREEN (-5800 5725);
DISPLAY INVISIBLE (-5800 5725);
FORCEPROP 1 LAST HDL_TAP TRUE
J 2
(-6125 5550);
DISPLAY 0.872340 (-6125 5550);
DISPLAY INVISIBLE (-6125 5550);
FORCEPROP 1 LAST PATH I247
J 2
(-5798 5675);
DISPLAY 0.872340 (-5798 5675);
PAINT GREEN (-5798 5675);
DISPLAY INVISIBLE (-5798 5675);
FORCEADD TAP..1
R 2
(-6000 5925);
FORCEPROP 3 LASTPIN (-5950 5925) SIG_NAME M_F_CPU0_SA_DQS_DN<0>
J 0
(-5940 5935);
DISPLAY 0.659574 (-5940 5935);
PAINT MONO (-5940 5935);
DISPLAY INVISIBLE (-5940 5935);
FORCEPROP 1 LASTPIN (-5950 5925) BN 0
J 2
(-5938 5933);
DISPLAY 0.489362 (-5938 5933);
PAINT GREEN (-5938 5933);
FORCEPROP 2 LAST CDS_LIB mstr_standard
J 2
(-6000 5925);
DISPLAY 0.723404 (-6000 5925);
PAINT MONO (-6000 5925);
DISPLAY INVISIBLE (-6000 5925);
FORCEPROP 1 LAST BODY_TYPE PLUMBING
J 2
(-6000 5975);
DISPLAY 0.872340 (-6000 5975);
PAINT GREEN (-6000 5975);
DISPLAY INVISIBLE (-6000 5975);
FORCEPROP 1 LAST HDL_TAP TRUE
J 2
(-6325 5800);
DISPLAY 0.872340 (-6325 5800);
DISPLAY INVISIBLE (-6325 5800);
FORCEPROP 1 LAST PATH I248
J 2
(-5998 5925);
DISPLAY 0.872340 (-5998 5925);
PAINT GREEN (-5998 5925);
DISPLAY INVISIBLE (-5998 5925);
FORCEADD TAP..1
R 2
(-6000 5825);
FORCEPROP 3 LASTPIN (-5950 5825) SIG_NAME M_F_CPU0_SA_DQS_DN<1>
J 0
(-5940 5835);
DISPLAY 0.659574 (-5940 5835);
PAINT MONO (-5940 5835);
DISPLAY INVISIBLE (-5940 5835);
FORCEPROP 1 LASTPIN (-5950 5825) BN 1
J 2
(-5938 5833);
DISPLAY 0.489362 (-5938 5833);
PAINT GREEN (-5938 5833);
FORCEPROP 2 LAST CDS_LIB mstr_standard
J 2
(-6000 5825);
DISPLAY 0.723404 (-6000 5825);
PAINT MONO (-6000 5825);
DISPLAY INVISIBLE (-6000 5825);
FORCEPROP 1 LAST BODY_TYPE PLUMBING
J 2
(-6000 5875);
DISPLAY 0.872340 (-6000 5875);
PAINT GREEN (-6000 5875);
DISPLAY INVISIBLE (-6000 5875);
FORCEPROP 1 LAST HDL_TAP TRUE
J 2
(-6325 5700);
DISPLAY 0.872340 (-6325 5700);
DISPLAY INVISIBLE (-6325 5700);
FORCEPROP 1 LAST PATH I249
J 2
(-5998 5825);
DISPLAY 0.872340 (-5998 5825);
PAINT GREEN (-5998 5825);
DISPLAY INVISIBLE (-5998 5825);
FORCEADD TAP..1
R 2
(-6000 5725);
FORCEPROP 3 LASTPIN (-5950 5725) SIG_NAME M_F_CPU0_SA_DQS_DN<2>
J 0
(-5940 5735);
DISPLAY 0.659574 (-5940 5735);
PAINT MONO (-5940 5735);
DISPLAY INVISIBLE (-5940 5735);
FORCEPROP 1 LASTPIN (-5950 5725) BN 2
J 2
(-5938 5733);
DISPLAY 0.489362 (-5938 5733);
PAINT GREEN (-5938 5733);
FORCEPROP 2 LAST CDS_LIB mstr_standard
J 2
(-6000 5725);
DISPLAY 0.723404 (-6000 5725);
PAINT MONO (-6000 5725);
DISPLAY INVISIBLE (-6000 5725);
FORCEPROP 1 LAST BODY_TYPE PLUMBING
J 2
(-6000 5775);
DISPLAY 0.872340 (-6000 5775);
PAINT GREEN (-6000 5775);
DISPLAY INVISIBLE (-6000 5775);
FORCEPROP 1 LAST HDL_TAP TRUE
J 2
(-6325 5600);
DISPLAY 0.872340 (-6325 5600);
DISPLAY INVISIBLE (-6325 5600);
FORCEPROP 1 LAST PATH I250
J 2
(-5998 5725);
DISPLAY 0.872340 (-5998 5725);
PAINT GREEN (-5998 5725);
DISPLAY INVISIBLE (-5998 5725);
FORCEADD TAP..1
R 2
(-5800 5575);
FORCEPROP 3 LASTPIN (-5750 5575) SIG_NAME M_F_CPU0_SA_DQS_DP<4>
J 0
(-5740 5585);
DISPLAY 0.659574 (-5740 5585);
PAINT MONO (-5740 5585);
DISPLAY INVISIBLE (-5740 5585);
FORCEPROP 1 LASTPIN (-5750 5575) BN 4
J 2
(-5738 5583);
DISPLAY 0.489362 (-5738 5583);
PAINT GREEN (-5738 5583);
FORCEPROP 2 LAST CDS_LIB mstr_standard
J 2
(-5800 5575);
DISPLAY 0.723404 (-5800 5575);
PAINT MONO (-5800 5575);
DISPLAY INVISIBLE (-5800 5575);
FORCEPROP 1 LAST BODY_TYPE PLUMBING
J 2
(-5800 5625);
DISPLAY 0.872340 (-5800 5625);
PAINT GREEN (-5800 5625);
DISPLAY INVISIBLE (-5800 5625);
FORCEPROP 1 LAST HDL_TAP TRUE
J 2
(-6125 5450);
DISPLAY 0.872340 (-6125 5450);
DISPLAY INVISIBLE (-6125 5450);
FORCEPROP 1 LAST PATH I251
J 2
(-5798 5575);
DISPLAY 0.872340 (-5798 5575);
PAINT GREEN (-5798 5575);
DISPLAY INVISIBLE (-5798 5575);
FORCEADD TAP..1
R 2
(-5800 5475);
FORCEPROP 3 LASTPIN (-5750 5475) SIG_NAME M_F_CPU0_SA_DQS_DP<5>
J 0
(-5740 5485);
DISPLAY 0.659574 (-5740 5485);
PAINT MONO (-5740 5485);
DISPLAY INVISIBLE (-5740 5485);
FORCEPROP 1 LASTPIN (-5750 5475) BN 5
J 2
(-5738 5483);
DISPLAY 0.489362 (-5738 5483);
PAINT GREEN (-5738 5483);
FORCEPROP 2 LAST CDS_LIB mstr_standard
J 2
(-5800 5475);
DISPLAY 0.723404 (-5800 5475);
PAINT MONO (-5800 5475);
DISPLAY INVISIBLE (-5800 5475);
FORCEPROP 1 LAST BODY_TYPE PLUMBING
J 2
(-5800 5525);
DISPLAY 0.872340 (-5800 5525);
PAINT GREEN (-5800 5525);
DISPLAY INVISIBLE (-5800 5525);
FORCEPROP 1 LAST HDL_TAP TRUE
J 2
(-6125 5350);
DISPLAY 0.872340 (-6125 5350);
DISPLAY INVISIBLE (-6125 5350);
FORCEPROP 1 LAST PATH I252
J 2
(-5798 5475);
DISPLAY 0.872340 (-5798 5475);
PAINT GREEN (-5798 5475);
DISPLAY INVISIBLE (-5798 5475);
FORCEADD TAP..1
R 2
(-5800 5375);
FORCEPROP 3 LASTPIN (-5750 5375) SIG_NAME M_F_CPU0_SA_DQS_DP<6>
J 0
(-5740 5385);
DISPLAY 0.659574 (-5740 5385);
PAINT MONO (-5740 5385);
DISPLAY INVISIBLE (-5740 5385);
FORCEPROP 1 LASTPIN (-5750 5375) BN 6
J 2
(-5738 5383);
DISPLAY 0.489362 (-5738 5383);
PAINT GREEN (-5738 5383);
FORCEPROP 2 LAST CDS_LIB mstr_standard
J 2
(-5800 5375);
DISPLAY 0.723404 (-5800 5375);
PAINT MONO (-5800 5375);
DISPLAY INVISIBLE (-5800 5375);
FORCEPROP 1 LAST BODY_TYPE PLUMBING
J 2
(-5800 5425);
DISPLAY 0.872340 (-5800 5425);
PAINT GREEN (-5800 5425);
DISPLAY INVISIBLE (-5800 5425);
FORCEPROP 1 LAST HDL_TAP TRUE
J 2
(-6125 5250);
DISPLAY 0.872340 (-6125 5250);
DISPLAY INVISIBLE (-6125 5250);
FORCEPROP 1 LAST PATH I253
J 2
(-5798 5375);
DISPLAY 0.872340 (-5798 5375);
PAINT GREEN (-5798 5375);
DISPLAY INVISIBLE (-5798 5375);
FORCEADD TAP..1
R 2
(-5800 5275);
FORCEPROP 3 LASTPIN (-5750 5275) SIG_NAME M_F_CPU0_SA_DQS_DP<7>
J 0
(-5740 5285);
DISPLAY 0.659574 (-5740 5285);
PAINT MONO (-5740 5285);
DISPLAY INVISIBLE (-5740 5285);
FORCEPROP 1 LASTPIN (-5750 5275) BN 7
J 2
(-5738 5283);
DISPLAY 0.489362 (-5738 5283);
PAINT GREEN (-5738 5283);
FORCEPROP 2 LAST CDS_LIB mstr_standard
J 2
(-5800 5275);
DISPLAY 0.723404 (-5800 5275);
PAINT MONO (-5800 5275);
DISPLAY INVISIBLE (-5800 5275);
FORCEPROP 1 LAST BODY_TYPE PLUMBING
J 2
(-5800 5325);
DISPLAY 0.872340 (-5800 5325);
PAINT GREEN (-5800 5325);
DISPLAY INVISIBLE (-5800 5325);
FORCEPROP 1 LAST HDL_TAP TRUE
J 2
(-6125 5150);
DISPLAY 0.872340 (-6125 5150);
DISPLAY INVISIBLE (-6125 5150);
FORCEPROP 1 LAST PATH I254
J 2
(-5798 5275);
DISPLAY 0.872340 (-5798 5275);
PAINT GREEN (-5798 5275);
DISPLAY INVISIBLE (-5798 5275);
FORCEADD TAP..1
R 2
(-5800 5175);
FORCEPROP 3 LASTPIN (-5750 5175) SIG_NAME M_F_CPU0_SA_DQS_DP<8>
J 0
(-5740 5185);
DISPLAY 0.659574 (-5740 5185);
PAINT MONO (-5740 5185);
DISPLAY INVISIBLE (-5740 5185);
FORCEPROP 1 LASTPIN (-5750 5175) BN 8
J 2
(-5738 5183);
DISPLAY 0.489362 (-5738 5183);
PAINT GREEN (-5738 5183);
FORCEPROP 2 LAST CDS_LIB mstr_standard
J 2
(-5800 5175);
DISPLAY 0.723404 (-5800 5175);
PAINT MONO (-5800 5175);
DISPLAY INVISIBLE (-5800 5175);
FORCEPROP 1 LAST BODY_TYPE PLUMBING
J 2
(-5800 5225);
DISPLAY 0.872340 (-5800 5225);
PAINT GREEN (-5800 5225);
DISPLAY INVISIBLE (-5800 5225);
FORCEPROP 1 LAST HDL_TAP TRUE
J 2
(-6125 5050);
DISPLAY 0.872340 (-6125 5050);
DISPLAY INVISIBLE (-6125 5050);
FORCEPROP 1 LAST PATH I255
J 2
(-5798 5175);
DISPLAY 0.872340 (-5798 5175);
PAINT GREEN (-5798 5175);
DISPLAY INVISIBLE (-5798 5175);
FORCEADD TAP..1
R 2
(-6000 5625);
FORCEPROP 3 LASTPIN (-5950 5625) SIG_NAME M_F_CPU0_SA_DQS_DN<3>
J 0
(-5940 5635);
DISPLAY 0.659574 (-5940 5635);
PAINT MONO (-5940 5635);
DISPLAY INVISIBLE (-5940 5635);
FORCEPROP 1 LASTPIN (-5950 5625) BN 3
J 2
(-5938 5633);
DISPLAY 0.489362 (-5938 5633);
PAINT GREEN (-5938 5633);
FORCEPROP 2 LAST CDS_LIB mstr_standard
J 2
(-6000 5625);
DISPLAY 0.723404 (-6000 5625);
PAINT MONO (-6000 5625);
DISPLAY INVISIBLE (-6000 5625);
FORCEPROP 1 LAST BODY_TYPE PLUMBING
J 2
(-6000 5675);
DISPLAY 0.872340 (-6000 5675);
PAINT GREEN (-6000 5675);
DISPLAY INVISIBLE (-6000 5675);
FORCEPROP 1 LAST HDL_TAP TRUE
J 2
(-6325 5500);
DISPLAY 0.872340 (-6325 5500);
DISPLAY INVISIBLE (-6325 5500);
FORCEPROP 1 LAST PATH I256
J 2
(-5998 5625);
DISPLAY 0.872340 (-5998 5625);
PAINT GREEN (-5998 5625);
DISPLAY INVISIBLE (-5998 5625);
FORCEADD TAP..1
R 2
(-6000 5525);
FORCEPROP 3 LASTPIN (-5950 5525) SIG_NAME M_F_CPU0_SA_DQS_DN<4>
J 0
(-5940 5535);
DISPLAY 0.659574 (-5940 5535);
PAINT MONO (-5940 5535);
DISPLAY INVISIBLE (-5940 5535);
FORCEPROP 1 LASTPIN (-5950 5525) BN 4
J 2
(-5938 5533);
DISPLAY 0.489362 (-5938 5533);
PAINT GREEN (-5938 5533);
FORCEPROP 2 LAST CDS_LIB mstr_standard
J 2
(-6000 5525);
DISPLAY 0.723404 (-6000 5525);
PAINT MONO (-6000 5525);
DISPLAY INVISIBLE (-6000 5525);
FORCEPROP 1 LAST BODY_TYPE PLUMBING
J 2
(-6000 5575);
DISPLAY 0.872340 (-6000 5575);
PAINT GREEN (-6000 5575);
DISPLAY INVISIBLE (-6000 5575);
FORCEPROP 1 LAST HDL_TAP TRUE
J 2
(-6325 5400);
DISPLAY 0.872340 (-6325 5400);
DISPLAY INVISIBLE (-6325 5400);
FORCEPROP 1 LAST PATH I257
J 2
(-5998 5525);
DISPLAY 0.872340 (-5998 5525);
PAINT GREEN (-5998 5525);
DISPLAY INVISIBLE (-5998 5525);
FORCEADD TAP..1
R 2
(-6000 5425);
FORCEPROP 3 LASTPIN (-5950 5425) SIG_NAME M_F_CPU0_SA_DQS_DN<5>
J 0
(-5940 5435);
DISPLAY 0.659574 (-5940 5435);
PAINT MONO (-5940 5435);
DISPLAY INVISIBLE (-5940 5435);
FORCEPROP 1 LASTPIN (-5950 5425) BN 5
J 2
(-5938 5433);
DISPLAY 0.489362 (-5938 5433);
PAINT GREEN (-5938 5433);
FORCEPROP 2 LAST CDS_LIB mstr_standard
J 2
(-6000 5425);
DISPLAY 0.723404 (-6000 5425);
PAINT MONO (-6000 5425);
DISPLAY INVISIBLE (-6000 5425);
FORCEPROP 1 LAST BODY_TYPE PLUMBING
J 2
(-6000 5475);
DISPLAY 0.872340 (-6000 5475);
PAINT GREEN (-6000 5475);
DISPLAY INVISIBLE (-6000 5475);
FORCEPROP 1 LAST HDL_TAP TRUE
J 2
(-6325 5300);
DISPLAY 0.872340 (-6325 5300);
DISPLAY INVISIBLE (-6325 5300);
FORCEPROP 1 LAST PATH I258
J 2
(-5998 5425);
DISPLAY 0.872340 (-5998 5425);
PAINT GREEN (-5998 5425);
DISPLAY INVISIBLE (-5998 5425);
FORCEADD TAP..1
R 2
(-6000 5325);
FORCEPROP 3 LASTPIN (-5950 5325) SIG_NAME M_F_CPU0_SA_DQS_DN<6>
J 0
(-5940 5335);
DISPLAY 0.659574 (-5940 5335);
PAINT MONO (-5940 5335);
DISPLAY INVISIBLE (-5940 5335);
FORCEPROP 1 LASTPIN (-5950 5325) BN 6
J 2
(-5938 5333);
DISPLAY 0.489362 (-5938 5333);
PAINT GREEN (-5938 5333);
FORCEPROP 2 LAST CDS_LIB mstr_standard
J 2
(-6000 5325);
DISPLAY 0.723404 (-6000 5325);
PAINT MONO (-6000 5325);
DISPLAY INVISIBLE (-6000 5325);
FORCEPROP 1 LAST BODY_TYPE PLUMBING
J 2
(-6000 5375);
DISPLAY 0.872340 (-6000 5375);
PAINT GREEN (-6000 5375);
DISPLAY INVISIBLE (-6000 5375);
FORCEPROP 1 LAST HDL_TAP TRUE
J 2
(-6325 5200);
DISPLAY 0.872340 (-6325 5200);
DISPLAY INVISIBLE (-6325 5200);
FORCEPROP 1 LAST PATH I259
J 2
(-5998 5325);
DISPLAY 0.872340 (-5998 5325);
PAINT GREEN (-5998 5325);
DISPLAY INVISIBLE (-5998 5325);
FORCEADD TAP..1
R 2
(-6000 5125);
FORCEPROP 3 LASTPIN (-5950 5125) SIG_NAME M_F_CPU0_SA_DQS_DN<8>
J 0
(-5940 5135);
DISPLAY 0.659574 (-5940 5135);
PAINT MONO (-5940 5135);
DISPLAY INVISIBLE (-5940 5135);
FORCEPROP 1 LASTPIN (-5950 5125) BN 8
J 2
(-5938 5133);
DISPLAY 0.489362 (-5938 5133);
PAINT GREEN (-5938 5133);
FORCEPROP 2 LAST CDS_LIB mstr_standard
J 2
(-6000 5125);
DISPLAY 0.723404 (-6000 5125);
PAINT MONO (-6000 5125);
DISPLAY INVISIBLE (-6000 5125);
FORCEPROP 1 LAST BODY_TYPE PLUMBING
J 2
(-6000 5175);
DISPLAY 0.872340 (-6000 5175);
PAINT GREEN (-6000 5175);
DISPLAY INVISIBLE (-6000 5175);
FORCEPROP 1 LAST HDL_TAP TRUE
J 2
(-6325 5000);
DISPLAY 0.872340 (-6325 5000);
DISPLAY INVISIBLE (-6325 5000);
FORCEPROP 1 LAST PATH I260
J 2
(-5998 5125);
DISPLAY 0.872340 (-5998 5125);
PAINT GREEN (-5998 5125);
DISPLAY INVISIBLE (-5998 5125);
FORCEADD TAP..1
R 2
(-6000 5225);
FORCEPROP 3 LASTPIN (-5950 5225) SIG_NAME M_F_CPU0_SA_DQS_DN<7>
J 0
(-5940 5235);
DISPLAY 0.659574 (-5940 5235);
PAINT MONO (-5940 5235);
DISPLAY INVISIBLE (-5940 5235);
FORCEPROP 1 LASTPIN (-5950 5225) BN 7
J 2
(-5938 5233);
DISPLAY 0.489362 (-5938 5233);
PAINT GREEN (-5938 5233);
FORCEPROP 2 LAST CDS_LIB mstr_standard
J 2
(-6000 5225);
DISPLAY 0.723404 (-6000 5225);
PAINT MONO (-6000 5225);
DISPLAY INVISIBLE (-6000 5225);
FORCEPROP 1 LAST BODY_TYPE PLUMBING
J 2
(-6000 5275);
DISPLAY 0.872340 (-6000 5275);
PAINT GREEN (-6000 5275);
DISPLAY INVISIBLE (-6000 5275);
FORCEPROP 1 LAST HDL_TAP TRUE
J 2
(-6325 5100);
DISPLAY 0.872340 (-6325 5100);
DISPLAY INVISIBLE (-6325 5100);
FORCEPROP 1 LAST PATH I261
J 2
(-5998 5225);
DISPLAY 0.872340 (-5998 5225);
PAINT GREEN (-5998 5225);
DISPLAY INVISIBLE (-5998 5225);
FORCEADD TAP..1
R 2
(-5800 5075);
FORCEPROP 3 LASTPIN (-5750 5075) SIG_NAME M_F_CPU0_SA_DQS_DP<9>
J 0
(-5740 5085);
DISPLAY 0.659574 (-5740 5085);
PAINT MONO (-5740 5085);
DISPLAY INVISIBLE (-5740 5085);
FORCEPROP 1 LASTPIN (-5750 5075) BN 9
J 2
(-5738 5083);
DISPLAY 0.489362 (-5738 5083);
PAINT GREEN (-5738 5083);
FORCEPROP 2 LAST CDS_LIB mstr_standard
J 2
(-5800 5075);
DISPLAY 0.723404 (-5800 5075);
PAINT MONO (-5800 5075);
DISPLAY INVISIBLE (-5800 5075);
FORCEPROP 1 LAST BODY_TYPE PLUMBING
J 2
(-5800 5125);
DISPLAY 0.872340 (-5800 5125);
PAINT GREEN (-5800 5125);
DISPLAY INVISIBLE (-5800 5125);
FORCEPROP 1 LAST HDL_TAP TRUE
J 2
(-6125 4950);
DISPLAY 0.872340 (-6125 4950);
DISPLAY INVISIBLE (-6125 4950);
FORCEPROP 1 LAST PATH I262
J 2
(-5798 5075);
DISPLAY 0.872340 (-5798 5075);
PAINT GREEN (-5798 5075);
DISPLAY INVISIBLE (-5798 5075);
FORCEADD TAP..1
R 2
(-5800 4925);
FORCEPROP 3 LASTPIN (-5750 4925) SIG_NAME M_F_CPU0_SB_DQS_DP<0>
J 0
(-5740 4935);
DISPLAY 0.659574 (-5740 4935);
PAINT MONO (-5740 4935);
DISPLAY INVISIBLE (-5740 4935);
FORCEPROP 1 LASTPIN (-5750 4925) BN 0
J 2
(-5738 4933);
DISPLAY 0.489362 (-5738 4933);
PAINT GREEN (-5738 4933);
FORCEPROP 2 LAST CDS_LIB mstr_standard
J 2
(-5800 4925);
DISPLAY 0.723404 (-5800 4925);
PAINT MONO (-5800 4925);
DISPLAY INVISIBLE (-5800 4925);
FORCEPROP 1 LAST BODY_TYPE PLUMBING
J 2
(-5800 4975);
DISPLAY 0.872340 (-5800 4975);
PAINT GREEN (-5800 4975);
DISPLAY INVISIBLE (-5800 4975);
FORCEPROP 1 LAST HDL_TAP TRUE
J 2
(-6125 4800);
DISPLAY 0.872340 (-6125 4800);
DISPLAY INVISIBLE (-6125 4800);
FORCEPROP 1 LAST PATH I263
J 2
(-5798 4925);
DISPLAY 0.872340 (-5798 4925);
PAINT GREEN (-5798 4925);
DISPLAY INVISIBLE (-5798 4925);
FORCEADD TAP..1
R 2
(-5800 4825);
FORCEPROP 3 LASTPIN (-5750 4825) SIG_NAME M_F_CPU0_SB_DQS_DP<1>
J 0
(-5740 4835);
DISPLAY 0.659574 (-5740 4835);
PAINT MONO (-5740 4835);
DISPLAY INVISIBLE (-5740 4835);
FORCEPROP 1 LASTPIN (-5750 4825) BN 1
J 2
(-5738 4833);
DISPLAY 0.489362 (-5738 4833);
PAINT GREEN (-5738 4833);
FORCEPROP 2 LAST CDS_LIB mstr_standard
J 2
(-5800 4825);
DISPLAY 0.723404 (-5800 4825);
PAINT MONO (-5800 4825);
DISPLAY INVISIBLE (-5800 4825);
FORCEPROP 1 LAST BODY_TYPE PLUMBING
J 2
(-5800 4875);
DISPLAY 0.872340 (-5800 4875);
PAINT GREEN (-5800 4875);
DISPLAY INVISIBLE (-5800 4875);
FORCEPROP 1 LAST HDL_TAP TRUE
J 2
(-6125 4700);
DISPLAY 0.872340 (-6125 4700);
DISPLAY INVISIBLE (-6125 4700);
FORCEPROP 1 LAST PATH I264
J 2
(-5798 4825);
DISPLAY 0.872340 (-5798 4825);
PAINT GREEN (-5798 4825);
DISPLAY INVISIBLE (-5798 4825);
FORCEADD TAP..1
R 2
(-5800 4725);
FORCEPROP 3 LASTPIN (-5750 4725) SIG_NAME M_F_CPU0_SB_DQS_DP<2>
J 0
(-5740 4735);
DISPLAY 0.659574 (-5740 4735);
PAINT MONO (-5740 4735);
DISPLAY INVISIBLE (-5740 4735);
FORCEPROP 1 LASTPIN (-5750 4725) BN 2
J 2
(-5738 4733);
DISPLAY 0.489362 (-5738 4733);
PAINT GREEN (-5738 4733);
FORCEPROP 2 LAST CDS_LIB mstr_standard
J 2
(-5800 4725);
DISPLAY 0.723404 (-5800 4725);
PAINT MONO (-5800 4725);
DISPLAY INVISIBLE (-5800 4725);
FORCEPROP 1 LAST BODY_TYPE PLUMBING
J 2
(-5800 4775);
DISPLAY 0.872340 (-5800 4775);
PAINT GREEN (-5800 4775);
DISPLAY INVISIBLE (-5800 4775);
FORCEPROP 1 LAST HDL_TAP TRUE
J 2
(-6125 4600);
DISPLAY 0.872340 (-6125 4600);
DISPLAY INVISIBLE (-6125 4600);
FORCEPROP 1 LAST PATH I265
J 2
(-5798 4725);
DISPLAY 0.872340 (-5798 4725);
PAINT GREEN (-5798 4725);
DISPLAY INVISIBLE (-5798 4725);
FORCEADD TAP..1
R 2
(-5800 4625);
FORCEPROP 3 LASTPIN (-5750 4625) SIG_NAME M_F_CPU0_SB_DQS_DP<3>
J 0
(-5740 4635);
DISPLAY 0.659574 (-5740 4635);
PAINT MONO (-5740 4635);
DISPLAY INVISIBLE (-5740 4635);
FORCEPROP 1 LASTPIN (-5750 4625) BN 3
J 2
(-5738 4633);
DISPLAY 0.489362 (-5738 4633);
PAINT GREEN (-5738 4633);
FORCEPROP 2 LAST CDS_LIB mstr_standard
J 2
(-5800 4625);
DISPLAY 0.723404 (-5800 4625);
PAINT MONO (-5800 4625);
DISPLAY INVISIBLE (-5800 4625);
FORCEPROP 1 LAST BODY_TYPE PLUMBING
J 2
(-5800 4675);
DISPLAY 0.872340 (-5800 4675);
PAINT GREEN (-5800 4675);
DISPLAY INVISIBLE (-5800 4675);
FORCEPROP 1 LAST HDL_TAP TRUE
J 2
(-6125 4500);
DISPLAY 0.872340 (-6125 4500);
DISPLAY INVISIBLE (-6125 4500);
FORCEPROP 1 LAST PATH I266
J 2
(-5798 4625);
DISPLAY 0.872340 (-5798 4625);
PAINT GREEN (-5798 4625);
DISPLAY INVISIBLE (-5798 4625);
FORCEADD TAP..1
R 2
(-6000 5025);
FORCEPROP 3 LASTPIN (-5950 5025) SIG_NAME M_F_CPU0_SA_DQS_DN<9>
J 0
(-5940 5035);
DISPLAY 0.659574 (-5940 5035);
PAINT MONO (-5940 5035);
DISPLAY INVISIBLE (-5940 5035);
FORCEPROP 1 LASTPIN (-5950 5025) BN 9
J 2
(-5938 5033);
DISPLAY 0.489362 (-5938 5033);
PAINT GREEN (-5938 5033);
FORCEPROP 2 LAST CDS_LIB mstr_standard
J 2
(-6000 5025);
DISPLAY 0.723404 (-6000 5025);
PAINT MONO (-6000 5025);
DISPLAY INVISIBLE (-6000 5025);
FORCEPROP 1 LAST BODY_TYPE PLUMBING
J 2
(-6000 5075);
DISPLAY 0.872340 (-6000 5075);
PAINT GREEN (-6000 5075);
DISPLAY INVISIBLE (-6000 5075);
FORCEPROP 1 LAST HDL_TAP TRUE
J 2
(-6325 4900);
DISPLAY 0.872340 (-6325 4900);
DISPLAY INVISIBLE (-6325 4900);
FORCEPROP 1 LAST PATH I267
J 2
(-5998 5025);
DISPLAY 0.872340 (-5998 5025);
PAINT GREEN (-5998 5025);
DISPLAY INVISIBLE (-5998 5025);
FORCEADD TAP..1
R 2
(-6000 4875);
FORCEPROP 3 LASTPIN (-5950 4875) SIG_NAME M_F_CPU0_SB_DQS_DN<0>
J 0
(-5940 4885);
DISPLAY 0.659574 (-5940 4885);
PAINT MONO (-5940 4885);
DISPLAY INVISIBLE (-5940 4885);
FORCEPROP 1 LASTPIN (-5950 4875) BN 0
J 2
(-5938 4883);
DISPLAY 0.489362 (-5938 4883);
PAINT GREEN (-5938 4883);
FORCEPROP 2 LAST CDS_LIB mstr_standard
J 2
(-6000 4875);
DISPLAY 0.723404 (-6000 4875);
PAINT MONO (-6000 4875);
DISPLAY INVISIBLE (-6000 4875);
FORCEPROP 1 LAST BODY_TYPE PLUMBING
J 2
(-6000 4925);
DISPLAY 0.872340 (-6000 4925);
PAINT GREEN (-6000 4925);
DISPLAY INVISIBLE (-6000 4925);
FORCEPROP 1 LAST HDL_TAP TRUE
J 2
(-6325 4750);
DISPLAY 0.872340 (-6325 4750);
DISPLAY INVISIBLE (-6325 4750);
FORCEPROP 1 LAST PATH I268
J 2
(-5998 4875);
DISPLAY 0.872340 (-5998 4875);
PAINT GREEN (-5998 4875);
DISPLAY INVISIBLE (-5998 4875);
FORCEADD TAP..1
R 2
(-6000 4775);
FORCEPROP 3 LASTPIN (-5950 4775) SIG_NAME M_F_CPU0_SB_DQS_DN<1>
J 0
(-5940 4785);
DISPLAY 0.659574 (-5940 4785);
PAINT MONO (-5940 4785);
DISPLAY INVISIBLE (-5940 4785);
FORCEPROP 1 LASTPIN (-5950 4775) BN 1
J 2
(-5938 4783);
DISPLAY 0.489362 (-5938 4783);
PAINT GREEN (-5938 4783);
FORCEPROP 2 LAST CDS_LIB mstr_standard
J 2
(-6000 4775);
DISPLAY 0.723404 (-6000 4775);
PAINT MONO (-6000 4775);
DISPLAY INVISIBLE (-6000 4775);
FORCEPROP 1 LAST BODY_TYPE PLUMBING
J 2
(-6000 4825);
DISPLAY 0.872340 (-6000 4825);
PAINT GREEN (-6000 4825);
DISPLAY INVISIBLE (-6000 4825);
FORCEPROP 1 LAST HDL_TAP TRUE
J 2
(-6325 4650);
DISPLAY 0.872340 (-6325 4650);
DISPLAY INVISIBLE (-6325 4650);
FORCEPROP 1 LAST PATH I269
J 2
(-5998 4775);
DISPLAY 0.872340 (-5998 4775);
PAINT GREEN (-5998 4775);
DISPLAY INVISIBLE (-5998 4775);
FORCEADD TAP..1
R 2
(-6000 4675);
FORCEPROP 3 LASTPIN (-5950 4675) SIG_NAME M_F_CPU0_SB_DQS_DN<2>
J 0
(-5940 4685);
DISPLAY 0.659574 (-5940 4685);
PAINT MONO (-5940 4685);
DISPLAY INVISIBLE (-5940 4685);
FORCEPROP 1 LASTPIN (-5950 4675) BN 2
J 2
(-5938 4683);
DISPLAY 0.489362 (-5938 4683);
PAINT GREEN (-5938 4683);
FORCEPROP 2 LAST CDS_LIB mstr_standard
J 2
(-6000 4675);
DISPLAY 0.723404 (-6000 4675);
PAINT MONO (-6000 4675);
DISPLAY INVISIBLE (-6000 4675);
FORCEPROP 1 LAST BODY_TYPE PLUMBING
J 2
(-6000 4725);
DISPLAY 0.872340 (-6000 4725);
PAINT GREEN (-6000 4725);
DISPLAY INVISIBLE (-6000 4725);
FORCEPROP 1 LAST HDL_TAP TRUE
J 2
(-6325 4550);
DISPLAY 0.872340 (-6325 4550);
DISPLAY INVISIBLE (-6325 4550);
FORCEPROP 1 LAST PATH I270
J 2
(-5998 4675);
DISPLAY 0.872340 (-5998 4675);
PAINT GREEN (-5998 4675);
DISPLAY INVISIBLE (-5998 4675);
FORCEADD TAP..1
R 2
(-5800 4525);
FORCEPROP 3 LASTPIN (-5750 4525) SIG_NAME M_F_CPU0_SB_DQS_DP<4>
J 0
(-5740 4535);
DISPLAY 0.659574 (-5740 4535);
PAINT MONO (-5740 4535);
DISPLAY INVISIBLE (-5740 4535);
FORCEPROP 1 LASTPIN (-5750 4525) BN 4
J 2
(-5738 4533);
DISPLAY 0.489362 (-5738 4533);
PAINT GREEN (-5738 4533);
FORCEPROP 2 LAST CDS_LIB mstr_standard
J 2
(-5800 4525);
DISPLAY 0.723404 (-5800 4525);
PAINT MONO (-5800 4525);
DISPLAY INVISIBLE (-5800 4525);
FORCEPROP 1 LAST BODY_TYPE PLUMBING
J 2
(-5800 4575);
DISPLAY 0.872340 (-5800 4575);
PAINT GREEN (-5800 4575);
DISPLAY INVISIBLE (-5800 4575);
FORCEPROP 1 LAST HDL_TAP TRUE
J 2
(-6125 4400);
DISPLAY 0.872340 (-6125 4400);
DISPLAY INVISIBLE (-6125 4400);
FORCEPROP 1 LAST PATH I271
J 2
(-5798 4525);
DISPLAY 0.872340 (-5798 4525);
PAINT GREEN (-5798 4525);
DISPLAY INVISIBLE (-5798 4525);
FORCEADD TAP..1
R 2
(-5800 4425);
FORCEPROP 3 LASTPIN (-5750 4425) SIG_NAME M_F_CPU0_SB_DQS_DP<5>
J 0
(-5740 4435);
DISPLAY 0.659574 (-5740 4435);
PAINT MONO (-5740 4435);
DISPLAY INVISIBLE (-5740 4435);
FORCEPROP 1 LASTPIN (-5750 4425) BN 5
J 2
(-5738 4433);
DISPLAY 0.489362 (-5738 4433);
PAINT GREEN (-5738 4433);
FORCEPROP 2 LAST CDS_LIB mstr_standard
J 2
(-5800 4425);
DISPLAY 0.723404 (-5800 4425);
PAINT MONO (-5800 4425);
DISPLAY INVISIBLE (-5800 4425);
FORCEPROP 1 LAST BODY_TYPE PLUMBING
J 2
(-5800 4475);
DISPLAY 0.872340 (-5800 4475);
PAINT GREEN (-5800 4475);
DISPLAY INVISIBLE (-5800 4475);
FORCEPROP 1 LAST HDL_TAP TRUE
J 2
(-6125 4300);
DISPLAY 0.872340 (-6125 4300);
DISPLAY INVISIBLE (-6125 4300);
FORCEPROP 1 LAST PATH I272
J 2
(-5798 4425);
DISPLAY 0.872340 (-5798 4425);
PAINT GREEN (-5798 4425);
DISPLAY INVISIBLE (-5798 4425);
FORCEADD TAP..1
R 2
(-5800 4325);
FORCEPROP 3 LASTPIN (-5750 4325) SIG_NAME M_F_CPU0_SB_DQS_DP<6>
J 0
(-5740 4335);
DISPLAY 0.659574 (-5740 4335);
PAINT MONO (-5740 4335);
DISPLAY INVISIBLE (-5740 4335);
FORCEPROP 1 LASTPIN (-5750 4325) BN 6
J 2
(-5738 4333);
DISPLAY 0.489362 (-5738 4333);
PAINT GREEN (-5738 4333);
FORCEPROP 2 LAST CDS_LIB mstr_standard
J 2
(-5800 4325);
DISPLAY 0.723404 (-5800 4325);
PAINT MONO (-5800 4325);
DISPLAY INVISIBLE (-5800 4325);
FORCEPROP 1 LAST BODY_TYPE PLUMBING
J 2
(-5800 4375);
DISPLAY 0.872340 (-5800 4375);
PAINT GREEN (-5800 4375);
DISPLAY INVISIBLE (-5800 4375);
FORCEPROP 1 LAST HDL_TAP TRUE
J 2
(-6125 4200);
DISPLAY 0.872340 (-6125 4200);
DISPLAY INVISIBLE (-6125 4200);
FORCEPROP 1 LAST PATH I273
J 2
(-5798 4325);
DISPLAY 0.872340 (-5798 4325);
PAINT GREEN (-5798 4325);
DISPLAY INVISIBLE (-5798 4325);
FORCEADD TAP..1
R 2
(-5800 4225);
FORCEPROP 3 LASTPIN (-5750 4225) SIG_NAME M_F_CPU0_SB_DQS_DP<7>
J 0
(-5740 4235);
DISPLAY 0.659574 (-5740 4235);
PAINT MONO (-5740 4235);
DISPLAY INVISIBLE (-5740 4235);
FORCEPROP 1 LASTPIN (-5750 4225) BN 7
J 2
(-5738 4233);
DISPLAY 0.489362 (-5738 4233);
PAINT GREEN (-5738 4233);
FORCEPROP 2 LAST CDS_LIB mstr_standard
J 2
(-5800 4225);
DISPLAY 0.723404 (-5800 4225);
PAINT MONO (-5800 4225);
DISPLAY INVISIBLE (-5800 4225);
FORCEPROP 1 LAST BODY_TYPE PLUMBING
J 2
(-5800 4275);
DISPLAY 0.872340 (-5800 4275);
PAINT GREEN (-5800 4275);
DISPLAY INVISIBLE (-5800 4275);
FORCEPROP 1 LAST HDL_TAP TRUE
J 2
(-6125 4100);
DISPLAY 0.872340 (-6125 4100);
DISPLAY INVISIBLE (-6125 4100);
FORCEPROP 1 LAST PATH I274
J 2
(-5798 4225);
DISPLAY 0.872340 (-5798 4225);
PAINT GREEN (-5798 4225);
DISPLAY INVISIBLE (-5798 4225);
FORCEADD TAP..1
R 2
(-5800 4125);
FORCEPROP 3 LASTPIN (-5750 4125) SIG_NAME M_F_CPU0_SB_DQS_DP<8>
J 0
(-5740 4135);
DISPLAY 0.659574 (-5740 4135);
PAINT MONO (-5740 4135);
DISPLAY INVISIBLE (-5740 4135);
FORCEPROP 1 LASTPIN (-5750 4125) BN 8
J 2
(-5738 4133);
DISPLAY 0.489362 (-5738 4133);
PAINT GREEN (-5738 4133);
FORCEPROP 2 LAST CDS_LIB mstr_standard
J 2
(-5800 4125);
DISPLAY 0.723404 (-5800 4125);
PAINT MONO (-5800 4125);
DISPLAY INVISIBLE (-5800 4125);
FORCEPROP 1 LAST BODY_TYPE PLUMBING
J 2
(-5800 4175);
DISPLAY 0.872340 (-5800 4175);
PAINT GREEN (-5800 4175);
DISPLAY INVISIBLE (-5800 4175);
FORCEPROP 1 LAST HDL_TAP TRUE
J 2
(-6125 4000);
DISPLAY 0.872340 (-6125 4000);
DISPLAY INVISIBLE (-6125 4000);
FORCEPROP 1 LAST PATH I275
J 2
(-5798 4125);
DISPLAY 0.872340 (-5798 4125);
PAINT GREEN (-5798 4125);
DISPLAY INVISIBLE (-5798 4125);
FORCEADD TAP..1
R 2
(-6000 4575);
FORCEPROP 3 LASTPIN (-5950 4575) SIG_NAME M_F_CPU0_SB_DQS_DN<3>
J 0
(-5940 4585);
DISPLAY 0.659574 (-5940 4585);
PAINT MONO (-5940 4585);
DISPLAY INVISIBLE (-5940 4585);
FORCEPROP 1 LASTPIN (-5950 4575) BN 3
J 2
(-5938 4583);
DISPLAY 0.489362 (-5938 4583);
PAINT GREEN (-5938 4583);
FORCEPROP 2 LAST CDS_LIB mstr_standard
J 2
(-6000 4575);
DISPLAY 0.723404 (-6000 4575);
PAINT MONO (-6000 4575);
DISPLAY INVISIBLE (-6000 4575);
FORCEPROP 1 LAST BODY_TYPE PLUMBING
J 2
(-6000 4625);
DISPLAY 0.872340 (-6000 4625);
PAINT GREEN (-6000 4625);
DISPLAY INVISIBLE (-6000 4625);
FORCEPROP 1 LAST HDL_TAP TRUE
J 2
(-6325 4450);
DISPLAY 0.872340 (-6325 4450);
DISPLAY INVISIBLE (-6325 4450);
FORCEPROP 1 LAST PATH I276
J 2
(-5998 4575);
DISPLAY 0.872340 (-5998 4575);
PAINT GREEN (-5998 4575);
DISPLAY INVISIBLE (-5998 4575);
FORCEADD TAP..1
R 2
(-6000 4475);
FORCEPROP 3 LASTPIN (-5950 4475) SIG_NAME M_F_CPU0_SB_DQS_DN<4>
J 0
(-5940 4485);
DISPLAY 0.659574 (-5940 4485);
PAINT MONO (-5940 4485);
DISPLAY INVISIBLE (-5940 4485);
FORCEPROP 1 LASTPIN (-5950 4475) BN 4
J 2
(-5938 4483);
DISPLAY 0.489362 (-5938 4483);
PAINT GREEN (-5938 4483);
FORCEPROP 2 LAST CDS_LIB mstr_standard
J 2
(-6000 4475);
DISPLAY 0.723404 (-6000 4475);
PAINT MONO (-6000 4475);
DISPLAY INVISIBLE (-6000 4475);
FORCEPROP 1 LAST BODY_TYPE PLUMBING
J 2
(-6000 4525);
DISPLAY 0.872340 (-6000 4525);
PAINT GREEN (-6000 4525);
DISPLAY INVISIBLE (-6000 4525);
FORCEPROP 1 LAST HDL_TAP TRUE
J 2
(-6325 4350);
DISPLAY 0.872340 (-6325 4350);
DISPLAY INVISIBLE (-6325 4350);
FORCEPROP 1 LAST PATH I277
J 2
(-5998 4475);
DISPLAY 0.872340 (-5998 4475);
PAINT GREEN (-5998 4475);
DISPLAY INVISIBLE (-5998 4475);
FORCEADD TAP..1
R 2
(-6000 4375);
FORCEPROP 3 LASTPIN (-5950 4375) SIG_NAME M_F_CPU0_SB_DQS_DN<5>
J 0
(-5940 4385);
DISPLAY 0.659574 (-5940 4385);
PAINT MONO (-5940 4385);
DISPLAY INVISIBLE (-5940 4385);
FORCEPROP 1 LASTPIN (-5950 4375) BN 5
J 2
(-5938 4383);
DISPLAY 0.489362 (-5938 4383);
PAINT GREEN (-5938 4383);
FORCEPROP 2 LAST CDS_LIB mstr_standard
J 2
(-6000 4375);
DISPLAY 0.723404 (-6000 4375);
PAINT MONO (-6000 4375);
DISPLAY INVISIBLE (-6000 4375);
FORCEPROP 1 LAST BODY_TYPE PLUMBING
J 2
(-6000 4425);
DISPLAY 0.872340 (-6000 4425);
PAINT GREEN (-6000 4425);
DISPLAY INVISIBLE (-6000 4425);
FORCEPROP 1 LAST HDL_TAP TRUE
J 2
(-6325 4250);
DISPLAY 0.872340 (-6325 4250);
DISPLAY INVISIBLE (-6325 4250);
FORCEPROP 1 LAST PATH I278
J 2
(-5998 4375);
DISPLAY 0.872340 (-5998 4375);
PAINT GREEN (-5998 4375);
DISPLAY INVISIBLE (-5998 4375);
FORCEADD TAP..1
R 2
(-6000 4275);
FORCEPROP 3 LASTPIN (-5950 4275) SIG_NAME M_F_CPU0_SB_DQS_DN<6>
J 0
(-5940 4285);
DISPLAY 0.659574 (-5940 4285);
PAINT MONO (-5940 4285);
DISPLAY INVISIBLE (-5940 4285);
FORCEPROP 1 LASTPIN (-5950 4275) BN 6
J 2
(-5938 4283);
DISPLAY 0.489362 (-5938 4283);
PAINT GREEN (-5938 4283);
FORCEPROP 2 LAST CDS_LIB mstr_standard
J 2
(-6000 4275);
DISPLAY 0.723404 (-6000 4275);
PAINT MONO (-6000 4275);
DISPLAY INVISIBLE (-6000 4275);
FORCEPROP 1 LAST BODY_TYPE PLUMBING
J 2
(-6000 4325);
DISPLAY 0.872340 (-6000 4325);
PAINT GREEN (-6000 4325);
DISPLAY INVISIBLE (-6000 4325);
FORCEPROP 1 LAST HDL_TAP TRUE
J 2
(-6325 4150);
DISPLAY 0.872340 (-6325 4150);
DISPLAY INVISIBLE (-6325 4150);
FORCEPROP 1 LAST PATH I279
J 2
(-5998 4275);
DISPLAY 0.872340 (-5998 4275);
PAINT GREEN (-5998 4275);
DISPLAY INVISIBLE (-5998 4275);
FORCEADD TAP..1
R 2
(-6000 4175);
FORCEPROP 3 LASTPIN (-5950 4175) SIG_NAME M_F_CPU0_SB_DQS_DN<7>
J 0
(-5940 4185);
DISPLAY 0.659574 (-5940 4185);
PAINT MONO (-5940 4185);
DISPLAY INVISIBLE (-5940 4185);
FORCEPROP 1 LASTPIN (-5950 4175) BN 7
J 2
(-5938 4183);
DISPLAY 0.489362 (-5938 4183);
PAINT GREEN (-5938 4183);
FORCEPROP 2 LAST CDS_LIB mstr_standard
J 2
(-6000 4175);
DISPLAY 0.723404 (-6000 4175);
PAINT MONO (-6000 4175);
DISPLAY INVISIBLE (-6000 4175);
FORCEPROP 1 LAST BODY_TYPE PLUMBING
J 2
(-6000 4225);
DISPLAY 0.872340 (-6000 4225);
PAINT GREEN (-6000 4225);
DISPLAY INVISIBLE (-6000 4225);
FORCEPROP 1 LAST HDL_TAP TRUE
J 2
(-6325 4050);
DISPLAY 0.872340 (-6325 4050);
DISPLAY INVISIBLE (-6325 4050);
FORCEPROP 1 LAST PATH I280
J 2
(-5998 4175);
DISPLAY 0.872340 (-5998 4175);
PAINT GREEN (-5998 4175);
DISPLAY INVISIBLE (-5998 4175);
FORCEADD OFFPAGE..3
R 2
(-6700 5950);
FORCEPROP 2 LAST $XR0 90 
J 0
(-6979 5950);
DISPLAY 0.638298 (-6979 5950);
PAINT MONO (-6979 5950);
FORCEPROP 2 LAST PATH I281
J 0
(-6975 6000);
DISPLAY 1.021277 (-6975 6000);
DISPLAY INVISIBLE (-6975 6000);
FORCEPROP 1 LAST COMMENT_BODY TRUE
J 2
(-6650 5850);
DISPLAY 0.872340 (-6650 5850);
PAINT GREEN (-6650 5850);
DISPLAY INVISIBLE (-6650 5850);
FORCEPROP 1 LAST OFFPAGE TRUE
J 2
(-7025 5825);
DISPLAY 0.872340 (-7025 5825);
PAINT GREEN (-7025 5825);
DISPLAY INVISIBLE (-7025 5825);
FORCEPROP 2 LAST CDS_LIB standard
J 0
(-6700 5950);
DISPLAY INVISIBLE (-6700 5950);
FORCEADD OFFPAGE..3
R 2
(-6700 6000);
FORCEPROP 2 LAST $XR0 90 
J 0
(-6979 6000);
DISPLAY 0.638298 (-6979 6000);
PAINT MONO (-6979 6000);
FORCEPROP 2 LAST PATH I282
J 0
(-6975 6050);
DISPLAY 1.021277 (-6975 6050);
DISPLAY INVISIBLE (-6975 6050);
FORCEPROP 1 LAST COMMENT_BODY TRUE
J 2
(-6650 5900);
DISPLAY 0.872340 (-6650 5900);
PAINT GREEN (-6650 5900);
DISPLAY INVISIBLE (-6650 5900);
FORCEPROP 1 LAST OFFPAGE TRUE
J 2
(-7025 5875);
DISPLAY 0.872340 (-7025 5875);
PAINT GREEN (-7025 5875);
DISPLAY INVISIBLE (-7025 5875);
FORCEPROP 2 LAST CDS_LIB standard
J 0
(-6700 6000);
DISPLAY INVISIBLE (-6700 6000);
FORCEADD OFFPAGE..3
R 2
(-6700 4900);
FORCEPROP 2 LAST $XR0 90 
J 0
(-6979 4900);
DISPLAY 0.638298 (-6979 4900);
PAINT MONO (-6979 4900);
FORCEPROP 2 LAST PATH I283
J 0
(-6975 4950);
DISPLAY 1.021277 (-6975 4950);
DISPLAY INVISIBLE (-6975 4950);
FORCEPROP 1 LAST COMMENT_BODY TRUE
J 2
(-6650 4800);
DISPLAY 0.872340 (-6650 4800);
PAINT GREEN (-6650 4800);
DISPLAY INVISIBLE (-6650 4800);
FORCEPROP 1 LAST OFFPAGE TRUE
J 2
(-7025 4775);
DISPLAY 0.872340 (-7025 4775);
PAINT GREEN (-7025 4775);
DISPLAY INVISIBLE (-7025 4775);
FORCEPROP 2 LAST CDS_LIB standard
J 0
(-6700 4900);
DISPLAY INVISIBLE (-6700 4900);
FORCEADD OFFPAGE..3
R 2
(-6700 4950);
FORCEPROP 2 LAST $XR0 90 
J 0
(-6979 4950);
DISPLAY 0.638298 (-6979 4950);
PAINT MONO (-6979 4950);
FORCEPROP 2 LAST PATH I284
J 0
(-6975 5000);
DISPLAY 1.021277 (-6975 5000);
DISPLAY INVISIBLE (-6975 5000);
FORCEPROP 1 LAST COMMENT_BODY TRUE
J 2
(-6650 4850);
DISPLAY 0.872340 (-6650 4850);
PAINT GREEN (-6650 4850);
DISPLAY INVISIBLE (-6650 4850);
FORCEPROP 1 LAST OFFPAGE TRUE
J 2
(-7025 4825);
DISPLAY 0.872340 (-7025 4825);
PAINT GREEN (-7025 4825);
DISPLAY INVISIBLE (-7025 4825);
FORCEPROP 2 LAST CDS_LIB standard
J 0
(-6700 4950);
DISPLAY INVISIBLE (-6700 4950);
FORCEADD TAP..1
R 2
(-5800 4025);
FORCEPROP 3 LASTPIN (-5750 4025) SIG_NAME M_F_CPU0_SB_DQS_DP<9>
J 0
(-5740 4035);
DISPLAY 0.659574 (-5740 4035);
PAINT MONO (-5740 4035);
DISPLAY INVISIBLE (-5740 4035);
FORCEPROP 1 LASTPIN (-5750 4025) BN 9
J 2
(-5738 4033);
DISPLAY 0.489362 (-5738 4033);
PAINT GREEN (-5738 4033);
FORCEPROP 2 LAST CDS_LIB mstr_standard
J 2
(-5800 4025);
DISPLAY 0.723404 (-5800 4025);
PAINT MONO (-5800 4025);
DISPLAY INVISIBLE (-5800 4025);
FORCEPROP 1 LAST BODY_TYPE PLUMBING
J 2
(-5800 4075);
DISPLAY 0.872340 (-5800 4075);
PAINT GREEN (-5800 4075);
DISPLAY INVISIBLE (-5800 4075);
FORCEPROP 1 LAST HDL_TAP TRUE
J 2
(-6125 3900);
DISPLAY 0.872340 (-6125 3900);
DISPLAY INVISIBLE (-6125 3900);
FORCEPROP 1 LAST PATH I285
J 2
(-5798 4025);
DISPLAY 0.872340 (-5798 4025);
PAINT GREEN (-5798 4025);
DISPLAY INVISIBLE (-5798 4025);
FORCEADD TAP..1
R 2
(-6000 3975);
FORCEPROP 3 LASTPIN (-5950 3975) SIG_NAME M_F_CPU0_SB_DQS_DN<9>
J 0
(-5940 3985);
DISPLAY 0.659574 (-5940 3985);
PAINT MONO (-5940 3985);
DISPLAY INVISIBLE (-5940 3985);
FORCEPROP 1 LASTPIN (-5950 3975) BN 9
J 2
(-5938 3983);
DISPLAY 0.489362 (-5938 3983);
PAINT GREEN (-5938 3983);
FORCEPROP 2 LAST CDS_LIB mstr_standard
J 2
(-6000 3975);
DISPLAY 0.723404 (-6000 3975);
PAINT MONO (-6000 3975);
DISPLAY INVISIBLE (-6000 3975);
FORCEPROP 1 LAST BODY_TYPE PLUMBING
J 2
(-6000 4025);
DISPLAY 0.872340 (-6000 4025);
PAINT GREEN (-6000 4025);
DISPLAY INVISIBLE (-6000 4025);
FORCEPROP 1 LAST HDL_TAP TRUE
J 2
(-6325 3850);
DISPLAY 0.872340 (-6325 3850);
DISPLAY INVISIBLE (-6325 3850);
FORCEPROP 1 LAST PATH I286
J 2
(-5998 3975);
DISPLAY 0.872340 (-5998 3975);
PAINT GREEN (-5998 3975);
DISPLAY INVISIBLE (-5998 3975);
FORCEADD TAP..1
R 2
(-6000 4075);
FORCEPROP 3 LASTPIN (-5950 4075) SIG_NAME M_F_CPU0_SB_DQS_DN<8>
J 0
(-5940 4085);
DISPLAY 0.659574 (-5940 4085);
PAINT MONO (-5940 4085);
DISPLAY INVISIBLE (-5940 4085);
FORCEPROP 1 LASTPIN (-5950 4075) BN 8
J 2
(-5938 4083);
DISPLAY 0.489362 (-5938 4083);
PAINT GREEN (-5938 4083);
FORCEPROP 2 LAST CDS_LIB mstr_standard
J 2
(-6000 4075);
DISPLAY 0.723404 (-6000 4075);
PAINT MONO (-6000 4075);
DISPLAY INVISIBLE (-6000 4075);
FORCEPROP 1 LAST BODY_TYPE PLUMBING
J 2
(-6000 4125);
DISPLAY 0.872340 (-6000 4125);
PAINT GREEN (-6000 4125);
DISPLAY INVISIBLE (-6000 4125);
FORCEPROP 1 LAST HDL_TAP TRUE
J 2
(-6325 3950);
DISPLAY 0.872340 (-6325 3950);
DISPLAY INVISIBLE (-6325 3950);
FORCEPROP 1 LAST PATH I287
J 2
(-5998 4075);
DISPLAY 0.872340 (-5998 4075);
PAINT GREEN (-5998 4075);
DISPLAY INVISIBLE (-5998 4075);
FORCEADD TAP..1
R 2
(-6000 3825);
FORCEPROP 3 LASTPIN (-5950 3825) SIG_NAME M_F_CPU0_SA_CA<0>
J 0
(-5940 3835);
DISPLAY 0.659574 (-5940 3835);
PAINT MONO (-5940 3835);
DISPLAY INVISIBLE (-5940 3835);
FORCEPROP 1 LASTPIN (-5950 3825) BN 0
J 2
(-5938 3833);
DISPLAY 0.489362 (-5938 3833);
PAINT GREEN (-5938 3833);
FORCEPROP 2 LAST CDS_LIB mstr_standard
J 0
(-6000 3825);
DISPLAY 0.723404 (-6000 3825);
PAINT MONO (-6000 3825);
DISPLAY INVISIBLE (-6000 3825);
FORCEPROP 1 LAST BODY_TYPE PLUMBING
J 2
(-6000 3875);
DISPLAY 0.872340 (-6000 3875);
PAINT GREEN (-6000 3875);
DISPLAY INVISIBLE (-6000 3875);
FORCEPROP 1 LAST HDL_TAP TRUE
J 2
(-6325 3700);
DISPLAY 0.872340 (-6325 3700);
DISPLAY INVISIBLE (-6325 3700);
FORCEPROP 1 LAST PATH I288
J 2
(-5998 3825);
DISPLAY 0.872340 (-5998 3825);
PAINT GREEN (-5998 3825);
DISPLAY INVISIBLE (-5998 3825);
FORCEADD TAP..1
R 2
(-6000 3775);
FORCEPROP 3 LASTPIN (-5950 3775) SIG_NAME M_F_CPU0_SA_CA<1>
J 0
(-5940 3785);
DISPLAY 0.659574 (-5940 3785);
PAINT MONO (-5940 3785);
DISPLAY INVISIBLE (-5940 3785);
FORCEPROP 1 LASTPIN (-5950 3775) BN 1
J 2
(-5938 3783);
DISPLAY 0.489362 (-5938 3783);
PAINT GREEN (-5938 3783);
FORCEPROP 2 LAST CDS_LIB mstr_standard
J 0
(-6000 3775);
DISPLAY 0.723404 (-6000 3775);
PAINT MONO (-6000 3775);
DISPLAY INVISIBLE (-6000 3775);
FORCEPROP 1 LAST BODY_TYPE PLUMBING
J 2
(-6000 3825);
DISPLAY 0.872340 (-6000 3825);
PAINT GREEN (-6000 3825);
DISPLAY INVISIBLE (-6000 3825);
FORCEPROP 1 LAST HDL_TAP TRUE
J 2
(-6325 3650);
DISPLAY 0.872340 (-6325 3650);
DISPLAY INVISIBLE (-6325 3650);
FORCEPROP 1 LAST PATH I289
J 2
(-5998 3775);
DISPLAY 0.872340 (-5998 3775);
PAINT GREEN (-5998 3775);
DISPLAY INVISIBLE (-5998 3775);
FORCEADD TAP..1
R 2
(-6000 3725);
FORCEPROP 3 LASTPIN (-5950 3725) SIG_NAME M_F_CPU0_SA_CA<2>
J 0
(-5940 3735);
DISPLAY 0.659574 (-5940 3735);
PAINT MONO (-5940 3735);
DISPLAY INVISIBLE (-5940 3735);
FORCEPROP 1 LASTPIN (-5950 3725) BN 2
J 2
(-5938 3733);
DISPLAY 0.489362 (-5938 3733);
PAINT GREEN (-5938 3733);
FORCEPROP 2 LAST CDS_LIB mstr_standard
J 0
(-6000 3725);
DISPLAY 0.723404 (-6000 3725);
PAINT MONO (-6000 3725);
DISPLAY INVISIBLE (-6000 3725);
FORCEPROP 1 LAST BODY_TYPE PLUMBING
J 2
(-6000 3775);
DISPLAY 0.872340 (-6000 3775);
PAINT GREEN (-6000 3775);
DISPLAY INVISIBLE (-6000 3775);
FORCEPROP 1 LAST HDL_TAP TRUE
J 2
(-6325 3600);
DISPLAY 0.872340 (-6325 3600);
DISPLAY INVISIBLE (-6325 3600);
FORCEPROP 1 LAST PATH I290
J 2
(-5998 3725);
DISPLAY 0.872340 (-5998 3725);
PAINT GREEN (-5998 3725);
DISPLAY INVISIBLE (-5998 3725);
FORCEADD TAP..1
R 2
(-6000 3675);
FORCEPROP 3 LASTPIN (-5950 3675) SIG_NAME M_F_CPU0_SA_CA<3>
J 0
(-5940 3685);
DISPLAY 0.659574 (-5940 3685);
PAINT MONO (-5940 3685);
DISPLAY INVISIBLE (-5940 3685);
FORCEPROP 1 LASTPIN (-5950 3675) BN 3
J 2
(-5938 3683);
DISPLAY 0.489362 (-5938 3683);
PAINT GREEN (-5938 3683);
FORCEPROP 2 LAST CDS_LIB mstr_standard
J 0
(-6000 3675);
DISPLAY 0.723404 (-6000 3675);
PAINT MONO (-6000 3675);
DISPLAY INVISIBLE (-6000 3675);
FORCEPROP 1 LAST BODY_TYPE PLUMBING
J 2
(-6000 3725);
DISPLAY 0.872340 (-6000 3725);
PAINT GREEN (-6000 3725);
DISPLAY INVISIBLE (-6000 3725);
FORCEPROP 1 LAST HDL_TAP TRUE
J 2
(-6325 3550);
DISPLAY 0.872340 (-6325 3550);
DISPLAY INVISIBLE (-6325 3550);
FORCEPROP 1 LAST PATH I291
J 2
(-5998 3675);
DISPLAY 0.872340 (-5998 3675);
PAINT GREEN (-5998 3675);
DISPLAY INVISIBLE (-5998 3675);
FORCEADD TAP..1
R 2
(-6000 3625);
FORCEPROP 3 LASTPIN (-5950 3625) SIG_NAME M_F_CPU0_SA_CA<4>
J 0
(-5940 3635);
DISPLAY 0.659574 (-5940 3635);
PAINT MONO (-5940 3635);
DISPLAY INVISIBLE (-5940 3635);
FORCEPROP 1 LASTPIN (-5950 3625) BN 4
J 2
(-5938 3633);
DISPLAY 0.489362 (-5938 3633);
PAINT GREEN (-5938 3633);
FORCEPROP 2 LAST CDS_LIB mstr_standard
J 0
(-6000 3625);
DISPLAY 0.723404 (-6000 3625);
PAINT MONO (-6000 3625);
DISPLAY INVISIBLE (-6000 3625);
FORCEPROP 1 LAST BODY_TYPE PLUMBING
J 2
(-6000 3675);
DISPLAY 0.872340 (-6000 3675);
PAINT GREEN (-6000 3675);
DISPLAY INVISIBLE (-6000 3675);
FORCEPROP 1 LAST HDL_TAP TRUE
J 2
(-6325 3500);
DISPLAY 0.872340 (-6325 3500);
DISPLAY INVISIBLE (-6325 3500);
FORCEPROP 1 LAST PATH I292
J 2
(-5998 3625);
DISPLAY 0.872340 (-5998 3625);
PAINT GREEN (-5998 3625);
DISPLAY INVISIBLE (-5998 3625);
FORCEADD TAP..1
R 2
(-6000 3575);
FORCEPROP 3 LASTPIN (-5950 3575) SIG_NAME M_F_CPU0_SA_CA<5>
J 0
(-5940 3585);
DISPLAY 0.659574 (-5940 3585);
PAINT MONO (-5940 3585);
DISPLAY INVISIBLE (-5940 3585);
FORCEPROP 1 LASTPIN (-5950 3575) BN 5
J 2
(-5938 3583);
DISPLAY 0.489362 (-5938 3583);
PAINT GREEN (-5938 3583);
FORCEPROP 2 LAST CDS_LIB mstr_standard
J 0
(-6000 3575);
DISPLAY 0.723404 (-6000 3575);
PAINT MONO (-6000 3575);
DISPLAY INVISIBLE (-6000 3575);
FORCEPROP 1 LAST BODY_TYPE PLUMBING
J 2
(-6000 3625);
DISPLAY 0.872340 (-6000 3625);
PAINT GREEN (-6000 3625);
DISPLAY INVISIBLE (-6000 3625);
FORCEPROP 1 LAST HDL_TAP TRUE
J 2
(-6325 3450);
DISPLAY 0.872340 (-6325 3450);
DISPLAY INVISIBLE (-6325 3450);
FORCEPROP 1 LAST PATH I293
J 2
(-5998 3575);
DISPLAY 0.872340 (-5998 3575);
PAINT GREEN (-5998 3575);
DISPLAY INVISIBLE (-5998 3575);
FORCEADD TAP..1
R 2
(-6000 3525);
FORCEPROP 3 LASTPIN (-5950 3525) SIG_NAME M_F_CPU0_SA_CA<6>
J 0
(-5940 3535);
DISPLAY 0.659574 (-5940 3535);
PAINT MONO (-5940 3535);
DISPLAY INVISIBLE (-5940 3535);
FORCEPROP 1 LASTPIN (-5950 3525) BN 6
J 2
(-5938 3533);
DISPLAY 0.489362 (-5938 3533);
PAINT GREEN (-5938 3533);
FORCEPROP 2 LAST CDS_LIB mstr_standard
J 0
(-6000 3525);
DISPLAY 0.723404 (-6000 3525);
PAINT MONO (-6000 3525);
DISPLAY INVISIBLE (-6000 3525);
FORCEPROP 1 LAST BODY_TYPE PLUMBING
J 2
(-6000 3575);
DISPLAY 0.872340 (-6000 3575);
PAINT GREEN (-6000 3575);
DISPLAY INVISIBLE (-6000 3575);
FORCEPROP 1 LAST HDL_TAP TRUE
J 2
(-6325 3400);
DISPLAY 0.872340 (-6325 3400);
DISPLAY INVISIBLE (-6325 3400);
FORCEPROP 1 LAST PATH I294
J 2
(-5998 3525);
DISPLAY 0.872340 (-5998 3525);
PAINT GREEN (-5998 3525);
DISPLAY INVISIBLE (-5998 3525);
FORCEADD TAP..1
R 2
(-6000 3425);
FORCEPROP 3 LASTPIN (-5950 3425) SIG_NAME M_F_CPU0_SB_CA<0>
J 0
(-5940 3435);
DISPLAY 0.659574 (-5940 3435);
PAINT MONO (-5940 3435);
DISPLAY INVISIBLE (-5940 3435);
FORCEPROP 1 LASTPIN (-5950 3425) BN 0
J 2
(-5938 3433);
DISPLAY 0.489362 (-5938 3433);
PAINT GREEN (-5938 3433);
FORCEPROP 2 LAST CDS_LIB mstr_standard
J 0
(-6000 3425);
DISPLAY 0.723404 (-6000 3425);
PAINT MONO (-6000 3425);
DISPLAY INVISIBLE (-6000 3425);
FORCEPROP 1 LAST BODY_TYPE PLUMBING
J 2
(-6000 3475);
DISPLAY 0.872340 (-6000 3475);
PAINT GREEN (-6000 3475);
DISPLAY INVISIBLE (-6000 3475);
FORCEPROP 1 LAST HDL_TAP TRUE
J 2
(-6325 3300);
DISPLAY 0.872340 (-6325 3300);
DISPLAY INVISIBLE (-6325 3300);
FORCEPROP 1 LAST PATH I295
J 2
(-5998 3425);
DISPLAY 0.872340 (-5998 3425);
PAINT GREEN (-5998 3425);
DISPLAY INVISIBLE (-5998 3425);
FORCEADD TAP..1
R 2
(-6000 3375);
FORCEPROP 3 LASTPIN (-5950 3375) SIG_NAME M_F_CPU0_SB_CA<1>
J 0
(-5940 3385);
DISPLAY 0.659574 (-5940 3385);
PAINT MONO (-5940 3385);
DISPLAY INVISIBLE (-5940 3385);
FORCEPROP 1 LASTPIN (-5950 3375) BN 1
J 2
(-5938 3383);
DISPLAY 0.489362 (-5938 3383);
PAINT GREEN (-5938 3383);
FORCEPROP 2 LAST CDS_LIB mstr_standard
J 0
(-6000 3375);
DISPLAY 0.723404 (-6000 3375);
PAINT MONO (-6000 3375);
DISPLAY INVISIBLE (-6000 3375);
FORCEPROP 1 LAST BODY_TYPE PLUMBING
J 2
(-6000 3425);
DISPLAY 0.872340 (-6000 3425);
PAINT GREEN (-6000 3425);
DISPLAY INVISIBLE (-6000 3425);
FORCEPROP 1 LAST HDL_TAP TRUE
J 2
(-6325 3250);
DISPLAY 0.872340 (-6325 3250);
DISPLAY INVISIBLE (-6325 3250);
FORCEPROP 1 LAST PATH I296
J 2
(-5998 3375);
DISPLAY 0.872340 (-5998 3375);
PAINT GREEN (-5998 3375);
DISPLAY INVISIBLE (-5998 3375);
FORCEADD TAP..1
R 2
(-6000 3325);
FORCEPROP 3 LASTPIN (-5950 3325) SIG_NAME M_F_CPU0_SB_CA<2>
J 0
(-5940 3335);
DISPLAY 0.659574 (-5940 3335);
PAINT MONO (-5940 3335);
DISPLAY INVISIBLE (-5940 3335);
FORCEPROP 1 LASTPIN (-5950 3325) BN 2
J 2
(-5938 3333);
DISPLAY 0.489362 (-5938 3333);
PAINT GREEN (-5938 3333);
FORCEPROP 2 LAST CDS_LIB mstr_standard
J 0
(-6000 3325);
DISPLAY 0.723404 (-6000 3325);
PAINT MONO (-6000 3325);
DISPLAY INVISIBLE (-6000 3325);
FORCEPROP 1 LAST BODY_TYPE PLUMBING
J 2
(-6000 3375);
DISPLAY 0.872340 (-6000 3375);
PAINT GREEN (-6000 3375);
DISPLAY INVISIBLE (-6000 3375);
FORCEPROP 1 LAST HDL_TAP TRUE
J 2
(-6325 3200);
DISPLAY 0.872340 (-6325 3200);
DISPLAY INVISIBLE (-6325 3200);
FORCEPROP 1 LAST PATH I297
J 2
(-5998 3325);
DISPLAY 0.872340 (-5998 3325);
PAINT GREEN (-5998 3325);
DISPLAY INVISIBLE (-5998 3325);
FORCEADD TAP..1
R 2
(-6000 3275);
FORCEPROP 3 LASTPIN (-5950 3275) SIG_NAME M_F_CPU0_SB_CA<3>
J 0
(-5940 3285);
DISPLAY 0.659574 (-5940 3285);
PAINT MONO (-5940 3285);
DISPLAY INVISIBLE (-5940 3285);
FORCEPROP 1 LASTPIN (-5950 3275) BN 3
J 2
(-5938 3283);
DISPLAY 0.489362 (-5938 3283);
PAINT GREEN (-5938 3283);
FORCEPROP 2 LAST CDS_LIB mstr_standard
J 0
(-6000 3275);
DISPLAY 0.723404 (-6000 3275);
PAINT MONO (-6000 3275);
DISPLAY INVISIBLE (-6000 3275);
FORCEPROP 1 LAST BODY_TYPE PLUMBING
J 2
(-6000 3325);
DISPLAY 0.872340 (-6000 3325);
PAINT GREEN (-6000 3325);
DISPLAY INVISIBLE (-6000 3325);
FORCEPROP 1 LAST HDL_TAP TRUE
J 2
(-6325 3150);
DISPLAY 0.872340 (-6325 3150);
DISPLAY INVISIBLE (-6325 3150);
FORCEPROP 1 LAST PATH I298
J 2
(-5998 3275);
DISPLAY 0.872340 (-5998 3275);
PAINT GREEN (-5998 3275);
DISPLAY INVISIBLE (-5998 3275);
FORCEADD TAP..1
R 2
(-6000 3225);
FORCEPROP 3 LASTPIN (-5950 3225) SIG_NAME M_F_CPU0_SB_CA<4>
J 0
(-5940 3235);
DISPLAY 0.659574 (-5940 3235);
PAINT MONO (-5940 3235);
DISPLAY INVISIBLE (-5940 3235);
FORCEPROP 1 LASTPIN (-5950 3225) BN 4
J 2
(-5938 3233);
DISPLAY 0.489362 (-5938 3233);
PAINT GREEN (-5938 3233);
FORCEPROP 2 LAST CDS_LIB mstr_standard
J 0
(-6000 3225);
DISPLAY 0.723404 (-6000 3225);
PAINT MONO (-6000 3225);
DISPLAY INVISIBLE (-6000 3225);
FORCEPROP 1 LAST BODY_TYPE PLUMBING
J 2
(-6000 3275);
DISPLAY 0.872340 (-6000 3275);
PAINT GREEN (-6000 3275);
DISPLAY INVISIBLE (-6000 3275);
FORCEPROP 1 LAST HDL_TAP TRUE
J 2
(-6325 3100);
DISPLAY 0.872340 (-6325 3100);
DISPLAY INVISIBLE (-6325 3100);
FORCEPROP 1 LAST PATH I299
J 2
(-5998 3225);
DISPLAY 0.872340 (-5998 3225);
PAINT GREEN (-5998 3225);
DISPLAY INVISIBLE (-5998 3225);
FORCEADD TAP..1
R 2
(-6000 3125);
FORCEPROP 3 LASTPIN (-5950 3125) SIG_NAME M_F_CPU0_SB_CA<6>
J 0
(-5940 3135);
DISPLAY 0.659574 (-5940 3135);
PAINT MONO (-5940 3135);
DISPLAY INVISIBLE (-5940 3135);
FORCEPROP 1 LASTPIN (-5950 3125) BN 6
J 2
(-5938 3133);
DISPLAY 0.489362 (-5938 3133);
PAINT GREEN (-5938 3133);
FORCEPROP 2 LAST CDS_LIB mstr_standard
J 0
(-6000 3125);
DISPLAY 0.723404 (-6000 3125);
PAINT MONO (-6000 3125);
DISPLAY INVISIBLE (-6000 3125);
FORCEPROP 1 LAST BODY_TYPE PLUMBING
J 2
(-6000 3175);
DISPLAY 0.872340 (-6000 3175);
PAINT GREEN (-6000 3175);
DISPLAY INVISIBLE (-6000 3175);
FORCEPROP 1 LAST HDL_TAP TRUE
J 2
(-6325 3000);
DISPLAY 0.872340 (-6325 3000);
DISPLAY INVISIBLE (-6325 3000);
FORCEPROP 1 LAST PATH I300
J 2
(-5998 3125);
DISPLAY 0.872340 (-5998 3125);
PAINT GREEN (-5998 3125);
DISPLAY INVISIBLE (-5998 3125);
FORCEADD TAP..1
R 2
(-6000 3175);
FORCEPROP 3 LASTPIN (-5950 3175) SIG_NAME M_F_CPU0_SB_CA<5>
J 0
(-5940 3185);
DISPLAY 0.659574 (-5940 3185);
PAINT MONO (-5940 3185);
DISPLAY INVISIBLE (-5940 3185);
FORCEPROP 1 LASTPIN (-5950 3175) BN 5
J 2
(-5938 3183);
DISPLAY 0.489362 (-5938 3183);
PAINT GREEN (-5938 3183);
FORCEPROP 2 LAST CDS_LIB mstr_standard
J 0
(-6000 3175);
DISPLAY 0.723404 (-6000 3175);
PAINT MONO (-6000 3175);
DISPLAY INVISIBLE (-6000 3175);
FORCEPROP 1 LAST BODY_TYPE PLUMBING
J 2
(-6000 3225);
DISPLAY 0.872340 (-6000 3225);
PAINT GREEN (-6000 3225);
DISPLAY INVISIBLE (-6000 3225);
FORCEPROP 1 LAST HDL_TAP TRUE
J 2
(-6325 3050);
DISPLAY 0.872340 (-6325 3050);
DISPLAY INVISIBLE (-6325 3050);
FORCEPROP 1 LAST PATH I301
J 2
(-5998 3175);
DISPLAY 0.872340 (-5998 3175);
PAINT GREEN (-5998 3175);
DISPLAY INVISIBLE (-5998 3175);
FORCEADD OFFPAGE..2
R 2
(-6600 3850);
FORCEPROP 2 LAST $XR0 90 
J 0
(-6854 3850);
DISPLAY 0.638298 (-6854 3850);
PAINT MONO (-6854 3850);
FORCEPROP 2 LAST PATH I302
J 0
(-6875 3900);
DISPLAY 1.021277 (-6875 3900);
DISPLAY INVISIBLE (-6875 3900);
FORCEPROP 1 LAST COMMENT_BODY TRUE
J 2
(-6555 3755);
DISPLAY 0.872340 (-6555 3755);
PAINT GREEN (-6555 3755);
DISPLAY INVISIBLE (-6555 3755);
FORCEPROP 1 LAST OFFPAGE TRUE
J 2
(-6925 3725);
DISPLAY 0.872340 (-6925 3725);
PAINT GREEN (-6925 3725);
DISPLAY INVISIBLE (-6925 3725);
FORCEPROP 2 LAST CDS_LIB standard
J 0
(-6600 3850);
DISPLAY INVISIBLE (-6600 3850);
FORCEADD OFFPAGE..2
R 2
(-6600 3450);
FORCEPROP 2 LAST $XR0 90 
J 0
(-6854 3450);
DISPLAY 0.638298 (-6854 3450);
PAINT MONO (-6854 3450);
FORCEPROP 2 LAST PATH I303
J 0
(-6875 3500);
DISPLAY 1.021277 (-6875 3500);
DISPLAY INVISIBLE (-6875 3500);
FORCEPROP 1 LAST COMMENT_BODY TRUE
J 2
(-6555 3355);
DISPLAY 0.872340 (-6555 3355);
PAINT GREEN (-6555 3355);
DISPLAY INVISIBLE (-6555 3355);
FORCEPROP 1 LAST OFFPAGE TRUE
J 2
(-6925 3325);
DISPLAY 0.872340 (-6925 3325);
PAINT GREEN (-6925 3325);
DISPLAY INVISIBLE (-6925 3325);
FORCEPROP 2 LAST CDS_LIB standard
J 0
(-6600 3450);
DISPLAY INVISIBLE (-6600 3450);
FORCEADD OFFPAGE..2
R 2
(-6600 2975);
FORCEPROP 2 LAST $XR0 90 
J 0
(-6854 2975);
DISPLAY 0.638298 (-6854 2975);
PAINT MONO (-6854 2975);
FORCEPROP 2 LAST PATH I304
J 0
(-6875 3025);
DISPLAY 1.021277 (-6875 3025);
DISPLAY INVISIBLE (-6875 3025);
FORCEPROP 1 LAST COMMENT_BODY TRUE
J 2
(-6555 2880);
DISPLAY 0.872340 (-6555 2880);
PAINT GREEN (-6555 2880);
DISPLAY INVISIBLE (-6555 2880);
FORCEPROP 1 LAST OFFPAGE TRUE
J 2
(-6925 2850);
DISPLAY 0.872340 (-6925 2850);
PAINT GREEN (-6925 2850);
DISPLAY INVISIBLE (-6925 2850);
FORCEPROP 2 LAST CDS_LIB standard
J 0
(-6600 2975);
DISPLAY INVISIBLE (-6600 2975);
FORCEADD OFFPAGE..2
R 2
(-6600 2925);
FORCEPROP 2 LAST $XR0 90 
J 0
(-6854 2925);
DISPLAY 0.638298 (-6854 2925);
PAINT MONO (-6854 2925);
FORCEPROP 2 LAST PATH I305
J 0
(-6875 2975);
DISPLAY 1.021277 (-6875 2975);
DISPLAY INVISIBLE (-6875 2975);
FORCEPROP 1 LAST COMMENT_BODY TRUE
J 2
(-6555 2830);
DISPLAY 0.872340 (-6555 2830);
PAINT GREEN (-6555 2830);
DISPLAY INVISIBLE (-6555 2830);
FORCEPROP 1 LAST OFFPAGE TRUE
J 2
(-6925 2800);
DISPLAY 0.872340 (-6925 2800);
PAINT GREEN (-6925 2800);
DISPLAY INVISIBLE (-6925 2800);
FORCEPROP 2 LAST CDS_LIB standard
J 0
(-6600 2925);
DISPLAY INVISIBLE (-6600 2925);
FORCEADD OFFPAGE..2
R 2
(-6600 2825);
FORCEPROP 2 LAST $XR0 90 
J 0
(-6854 2825);
DISPLAY 0.638298 (-6854 2825);
PAINT MONO (-6854 2825);
FORCEPROP 2 LAST PATH I306
J 0
(-6875 2875);
DISPLAY 1.021277 (-6875 2875);
DISPLAY INVISIBLE (-6875 2875);
FORCEPROP 1 LAST COMMENT_BODY TRUE
J 2
(-6555 2730);
DISPLAY 0.872340 (-6555 2730);
PAINT GREEN (-6555 2730);
DISPLAY INVISIBLE (-6555 2730);
FORCEPROP 1 LAST OFFPAGE TRUE
J 2
(-6925 2700);
DISPLAY 0.872340 (-6925 2700);
PAINT GREEN (-6925 2700);
DISPLAY INVISIBLE (-6925 2700);
FORCEPROP 2 LAST CDS_LIB standard
J 0
(-6600 2825);
DISPLAY INVISIBLE (-6600 2825);
FORCEADD OFFPAGE..2
R 2
(-6600 2775);
FORCEPROP 2 LAST $XR0 90 
J 0
(-6854 2775);
DISPLAY 0.638298 (-6854 2775);
PAINT MONO (-6854 2775);
FORCEPROP 2 LAST PATH I307
J 0
(-6875 2825);
DISPLAY 1.021277 (-6875 2825);
DISPLAY INVISIBLE (-6875 2825);
FORCEPROP 1 LAST COMMENT_BODY TRUE
J 2
(-6555 2680);
DISPLAY 0.872340 (-6555 2680);
PAINT GREEN (-6555 2680);
DISPLAY INVISIBLE (-6555 2680);
FORCEPROP 1 LAST OFFPAGE TRUE
J 2
(-6925 2650);
DISPLAY 0.872340 (-6925 2650);
PAINT GREEN (-6925 2650);
DISPLAY INVISIBLE (-6925 2650);
FORCEPROP 2 LAST CDS_LIB standard
J 0
(-6600 2775);
DISPLAY INVISIBLE (-6600 2775);
FORCEADD OFFPAGE..1
(-6600 2325);
FORCEPROP 2 LAST $XR0 90 
J 0
(-6821 2325);
DISPLAY 0.638298 (-6821 2325);
PAINT MONO (-6821 2325);
FORCEPROP 2 LAST PATH I308
J 0
(-6850 2375);
DISPLAY 1.021277 (-6850 2375);
DISPLAY INVISIBLE (-6850 2375);
FORCEPROP 1 LAST COMMENT_BODY TRUE
J 0
(-6475 2225);
DISPLAY 0.872340 (-6475 2225);
PAINT GREEN (-6475 2225);
DISPLAY INVISIBLE (-6475 2225);
FORCEPROP 1 LAST OFFPAGE TRUE
J 0
(-6275 2200);
DISPLAY 0.872340 (-6275 2200);
PAINT GREEN (-6275 2200);
DISPLAY INVISIBLE (-6275 2200);
FORCEPROP 2 LAST CDS_LIB standard
J 0
(-6600 2325);
DISPLAY INVISIBLE (-6600 2325);
FORCEADD OFFPAGE..1
(-6600 2675);
FORCEPROP 2 LAST $XR0 90 
J 0
(-6821 2675);
DISPLAY 0.638298 (-6821 2675);
PAINT MONO (-6821 2675);
FORCEPROP 2 LAST PATH I309
J 0
(-6850 2725);
DISPLAY 1.021277 (-6850 2725);
DISPLAY INVISIBLE (-6850 2725);
FORCEPROP 1 LAST COMMENT_BODY TRUE
J 0
(-6475 2575);
DISPLAY 0.872340 (-6475 2575);
PAINT GREEN (-6475 2575);
DISPLAY INVISIBLE (-6475 2575);
FORCEPROP 1 LAST OFFPAGE TRUE
J 0
(-6275 2550);
DISPLAY 0.872340 (-6275 2550);
PAINT GREEN (-6275 2550);
DISPLAY INVISIBLE (-6275 2550);
FORCEPROP 2 LAST CDS_LIB standard
J 0
(-6600 2675);
DISPLAY INVISIBLE (-6600 2675);
FORCEADD OFFPAGE..5
(-6600 2575);
FORCEPROP 2 LAST $XR0 90 
J 0
(-6854 2575);
DISPLAY 0.638298 (-6854 2575);
PAINT MONO (-6854 2575);
FORCEPROP 2 LAST PATH I310
J 0
(-6875 2625);
DISPLAY 1.021277 (-6875 2625);
DISPLAY INVISIBLE (-6875 2625);
FORCEPROP 1 LAST COMMENT_BODY TRUE
J 0
(-6500 2500);
DISPLAY 0.872340 (-6500 2500);
PAINT GREEN (-6500 2500);
DISPLAY INVISIBLE (-6500 2500);
FORCEPROP 1 LAST OFFPAGE TRUE
J 0
(-6275 2450);
DISPLAY 0.872340 (-6275 2450);
PAINT GREEN (-6275 2450);
DISPLAY INVISIBLE (-6275 2450);
FORCEPROP 2 LAST CDS_LIB mstr_standard
J 0
(-6600 2575);
DISPLAY INVISIBLE (-6600 2575);
FORCEADD OFFPAGE..2
R 2
(-6600 2475);
FORCEPROP 2 LAST $XR0 90 
J 0
(-6854 2475);
DISPLAY 0.638298 (-6854 2475);
PAINT MONO (-6854 2475);
FORCEPROP 2 LAST PATH I311
J 0
(-6875 2525);
DISPLAY 1.021277 (-6875 2525);
DISPLAY INVISIBLE (-6875 2525);
FORCEPROP 1 LAST COMMENT_BODY TRUE
J 2
(-6555 2380);
DISPLAY 0.872340 (-6555 2380);
PAINT GREEN (-6555 2380);
DISPLAY INVISIBLE (-6555 2380);
FORCEPROP 1 LAST OFFPAGE TRUE
J 2
(-6925 2350);
DISPLAY 0.872340 (-6925 2350);
PAINT GREEN (-6925 2350);
DISPLAY INVISIBLE (-6925 2350);
FORCEPROP 2 LAST CDS_LIB standard
J 0
(-6600 2475);
DISPLAY INVISIBLE (-6600 2475);
FORCEADD OFFPAGE..2
R 2
(-6600 2425);
FORCEPROP 2 LAST $XR0 90 
J 0
(-6854 2425);
DISPLAY 0.638298 (-6854 2425);
PAINT MONO (-6854 2425);
FORCEPROP 2 LAST PATH I312
J 0
(-6875 2475);
DISPLAY 1.021277 (-6875 2475);
DISPLAY INVISIBLE (-6875 2475);
FORCEPROP 1 LAST COMMENT_BODY TRUE
J 2
(-6555 2330);
DISPLAY 0.872340 (-6555 2330);
PAINT GREEN (-6555 2330);
DISPLAY INVISIBLE (-6555 2330);
FORCEPROP 1 LAST OFFPAGE TRUE
J 2
(-6925 2300);
DISPLAY 0.872340 (-6925 2300);
PAINT GREEN (-6925 2300);
DISPLAY INVISIBLE (-6925 2300);
FORCEPROP 2 LAST CDS_LIB standard
J 0
(-6600 2425);
DISPLAY INVISIBLE (-6600 2425);
FORCEADD OFFPAGE..5
(-6600 2225);
FORCEPROP 2 LAST $XR0 90 
J 0
(-6854 2225);
DISPLAY 0.638298 (-6854 2225);
PAINT MONO (-6854 2225);
FORCEPROP 2 LAST PATH I313
J 0
(-6875 2275);
DISPLAY 1.021277 (-6875 2275);
DISPLAY INVISIBLE (-6875 2275);
FORCEPROP 1 LAST COMMENT_BODY TRUE
J 0
(-6500 2150);
DISPLAY 0.872340 (-6500 2150);
PAINT GREEN (-6500 2150);
DISPLAY INVISIBLE (-6500 2150);
FORCEPROP 1 LAST OFFPAGE TRUE
J 0
(-6275 2100);
DISPLAY 0.872340 (-6275 2100);
PAINT GREEN (-6275 2100);
DISPLAY INVISIBLE (-6275 2100);
FORCEPROP 2 LAST CDS_LIB standard
J 0
(-6600 2225);
DISPLAY INVISIBLE (-6600 2225);
FORCEADD Q_RES..1
(-6925 2125);
FORCEPROP 1 LAST LOCATION R380
J 0
(-7250 2125);
DISPLAY 0.489362 (-7250 2125);
PAINT SKYBLUE (-7250 2125);
FORCEPROP 0 LAST $SEC 1
J 0
(-7100 2175);
DISPLAY 0.680851 (-7100 2175);
PAINT MONO (-7100 2175);
DISPLAY INVISIBLE (-7100 2175);
FORCEPROP 0 LAST CDS_SEC 1
J 0
(-7100 2175);
DISPLAY 1.021277 (-7100 2175);
DISPLAY INVISIBLE (-7100 2175);
FORCEPROP 1 LASTPIN (-7025 2125) $PN 1
J 0
(-7013 2137);
DISPLAY 0.489362 (-7013 2137);
PAINT MONO (-7013 2137);
FORCEPROP 1 LASTPIN (-6825 2125) $PN 2
J 0
(-6863 2137);
DISPLAY 0.489362 (-6863 2137);
PAINT MONO (-6863 2137);
FORCEPROP 1 LAST TOLERANCE 1%
J 0
(-6650 2125);
DISPLAY 0.489362 (-6650 2125);
PAINT SKYBLUE (-6650 2125);
FORCEPROP 1 LAST VALUE 15   
J 2
(-6600 2125);
DISPLAY 0.489362 (-6600 2125);
PAINT SKYBLUE (-6600 2125);
FORCEPROP 1 LAST PART_NUMBER CS01502FB11
J 0
(-6800 2100);
DISPLAY 0.489362 (-6800 2100);
PAINT SKYBLUE (-6800 2100);
FORCEPROP 1 LAST PACK_TYPE 0402LF
J 0
(-7250 2100);
DISPLAY 0.489362 (-7250 2100);
PAINT SKYBLUE (-7250 2100);
FORCEPROP 2 LAST CDS_LIB pure_quanta
J 0
(-6925 2125);
DISPLAY INVISIBLE (-6925 2125);
FORCEPROP 1 LAST PATH I314
J 0
(-6975 2275);
DISPLAY 0.978723 (-6975 2275);
PAINT WHITE (-6975 2275);
DISPLAY INVISIBLE (-6975 2275);
FORCEPROP 1 LAST WATTAGE 1/16W
J 2
(-6700 2250);
DISPLAY 0.638298 (-6700 2250);
PAINT SKYBLUE (-6700 2250);
DISPLAY INVISIBLE (-6700 2250);
FORCEPROP 1 LAST MATERIAL CHIP
J 0
(-7050 2250);
DISPLAY 0.638298 (-7050 2250);
PAINT SKYBLUE (-7050 2250);
DISPLAY INVISIBLE (-7050 2250);
FORCEADD OFFPAGE..1
(-7800 2125);
FORCEPROP 2 LAST $XR0 90 
J 0
(-8051 2125);
DISPLAY 0.638298 (-8051 2125);
PAINT MONO (-8051 2125);
FORCEPROP 2 LAST PATH I315
J 0
(-8075 2175);
DISPLAY 1.021277 (-8075 2175);
DISPLAY INVISIBLE (-8075 2175);
FORCEPROP 1 LAST COMMENT_BODY TRUE
J 0
(-7675 2025);
DISPLAY 0.872340 (-7675 2025);
PAINT GREEN (-7675 2025);
DISPLAY INVISIBLE (-7675 2025);
FORCEPROP 1 LAST OFFPAGE TRUE
J 0
(-7475 2000);
DISPLAY 0.872340 (-7475 2000);
PAINT GREEN (-7475 2000);
DISPLAY INVISIBLE (-7475 2000);
FORCEPROP 2 LAST CDS_LIB mstr_standard
J 0
(-7800 2125);
DISPLAY INVISIBLE (-7800 2125);
FORCEADD OFFPAGE..5
(-6600 2025);
FORCEPROP 2 LAST $XR0 90 
J 0
(-6854 2025);
DISPLAY 0.638298 (-6854 2025);
PAINT MONO (-6854 2025);
FORCEPROP 2 LAST PATH I316
J 0
(-6875 2075);
DISPLAY 1.021277 (-6875 2075);
DISPLAY INVISIBLE (-6875 2075);
FORCEPROP 1 LAST COMMENT_BODY TRUE
J 0
(-6500 1950);
DISPLAY 0.872340 (-6500 1950);
PAINT GREEN (-6500 1950);
DISPLAY INVISIBLE (-6500 1950);
FORCEPROP 1 LAST OFFPAGE TRUE
J 0
(-6275 1900);
DISPLAY 0.872340 (-6275 1900);
PAINT GREEN (-6275 1900);
DISPLAY INVISIBLE (-6275 1900);
FORCEPROP 2 LAST CDS_LIB standard
J 0
(-6600 2025);
DISPLAY INVISIBLE (-6600 2025);
FORCEADD QUANTA_TITLE_BLOCK_C..1
(-100 100);
FORCEPROP 0 LAST CDS_CON_LAST_MODIFIED Fri Mar 11 14:52:14 2022
J 0
(-1985 115);
DISPLAY INVISIBLE (-1985 115);
FORCEPROP 1 LAST CUSTOM_TXT_CDS <CON_LAST_MODIFIED>
J 0
(-1985 115);
DISPLAY 0.978723 (-1985 115);
FORCEPROP 2 LAST CUSTOM_TXT_CDS <XR_PAGE_TITLE>
J 0
(-7990 5350);
DISPLAY 0.638298 (-7990 5350);
PAINT PINK (-7990 5350);
DISPLAY INVISIBLE (-7990 5350);
FORCEPROP 1 LAST CUSTOM_TXT_CDS <NAME_2>
J 0
(-3275 150);
FORCEPROP 1 LAST CUSTOM_TXT_CDS <NAME_1>
J 0
(-3275 275);
FORCEPROP 1 LAST CUSTOM_TXT_CDS <Q_NUMBER>
J 0
(-1503 203);
DISPLAY 1.212766 (-1503 203);
FORCEPROP 1 LAST CUSTOM_TXT_CDS <Q_PROJ>
J 0
(-2482 202);
DISPLAY 1.212766 (-2482 202);
FORCEPROP 1 LAST CUSTOM_TXT_CDS <Q_REV>
J 0
(-284 203);
DISPLAY 1.212766 (-284 203);
FORCEPROP 1 LAST CUSTOM_TXT_CDS <CON_PAGE_NUM> OF <CON_TOTAL_PAGES>
J 0
(-546 118);
DISPLAY 0.978723 (-546 118);
FORCEPROP 1 LAST Q_TITLE CPU0 DDR CHF
J 0
(-9400 150);
DISPLAY 2.446809 (-9400 150);
PAINT GREEN (-9400 150);
FORCEPROP 1 LAST Q_DEPT BU9
J 1
(-3863 149);
DISPLAY 1.957447 (-3863 149);
PAINT GREEN (-3863 149);
FORCEPROP 2 LAST PAGE_BORDER TRUE
J 0
(-7990 5350);
DISPLAY 0.638298 (-7990 5350);
PAINT PINK (-7990 5350);
DISPLAY INVISIBLE (-7990 5350);
FORCEPROP 2 LAST CDS_LIB pure_quanta
J 0
(-100 100);
DISPLAY INVISIBLE (-100 100);
FORCEPROP 1 LAST CDS_LMAN_SYM_OUTLINE -9475,6775,100,-125
J 0
(-100 100);
DISPLAY 0.468085 (-100 100);
PAINT GREEN (-100 100);
DISPLAY INVISIBLE (-100 100);
FORCEPROP 1 LAST COMMENT_BODY TRUE
J 0
(-88 87);
DISPLAY 0.978723 (-88 87);
PAINT GREEN (-88 87);
DISPLAY INVISIBLE (-88 87);
FORCEPROP 2 LAST CDS_XR_PAGE_TITLE CR-15 : @T6G_MB_LIB.T6G(SCH_1):PAGE15
J 0
(-7990 5350);
DISPLAY 0.638298 (-7990 5350);
PAINT PINK (-7990 5350);
DISPLAY INVISIBLE (-7990 5350);
FORCEADD CAD_NOTE..1
(-7750 2425);
FORCEPROP 0 LAST L1 R1954 PLACE CLOSE TO CPU < 25MM
J 0
(-7900 2300);
DISPLAY 0.617021 (-7900 2300);
PAINT WHITE (-7900 2300);
FORCEPROP 2 LAST CDS_LIB pure_quanta_power
J 0
(-7750 2425);
DISPLAY INVISIBLE (-7750 2425);
FORCEPROP 1 LAST COMMENT_BODY TRUE
J 0
(-7725 2525);
DISPLAY 0.574468 (-7725 2525);
PAINT WHITE (-7725 2525);
DISPLAY INVISIBLE (-7725 2525);
WIRE 17 -1 (-3325 5550)(-3325 5500);
WIRE 17 -1 (-3325 5650)(-3325 5550);
WIRE 17 -1 (-3325 5500)(-3325 5450);
WIRE 17 -1 (-3325 5450)(-3325 5400);
WIRE 17 -1 (-3325 5700)(-3325 5650);
WIRE 17 -1 (-3325 5750)(-3325 5700);
WIRE 17 -1 (-3325 5400)(-3325 5350);
WIRE 17 -1 (-3325 5350)(-3325 5300);
WIRE 17 -1 (-3325 5800)(-3325 5750);
WIRE 17 -1 (-3325 5850)(-3325 5800);
WIRE 17 -1 (-3325 5300)(-3325 5250);
WIRE 17 -1 (-3325 5250)(-3325 5200);
WIRE 17 -1 (-3325 5900)(-3325 5850);
WIRE 17 -1 (-3325 5950)(-3325 5900);
WIRE 17 -1 (-3325 5100)(-3325 5200);
WIRE 17 -1 (-3325 5050)(-3325 5100);
WIRE 17 -1 (-3325 6000)(-3325 5950);
WIRE 17 -1 (-3325 6000)(-2700 6000);
FORCEPROP 2 LAST SIG_NAME M_F_CPU0_SA_DQ<31:0>
J 2
(-2760 6010);
DISPLAY 0.489362 (-2760 6010);
WIRE 17 -1 (-3325 5000)(-3325 5050);
WIRE 17 -1 (-3325 4950)(-3325 5000);
WIRE 17 -1 (-3325 4950)(-3325 4900);
WIRE 17 -1 (-3325 4900)(-3325 4850);
WIRE 17 -1 (-3325 4850)(-3325 4800);
WIRE 17 -1 (-3325 4800)(-3325 4750);
WIRE 17 -1 (-3325 4750)(-3325 4650);
WIRE 17 -1 (-3325 4650)(-3325 4600);
WIRE 17 -1 (-3325 4600)(-3325 4550);
WIRE 17 -1 (-3325 4550)(-3325 4500);
WIRE 17 -1 (-3325 4450)(-3325 4500);
WIRE 17 -1 (-3325 4400)(-3325 4450);
WIRE 17 -1 (-3325 4350)(-3325 4400);
WIRE 17 -1 (-3325 4300)(-3325 4350);
WIRE 17 -1 (-3325 4200)(-3325 4150);
WIRE 17 -1 (-3325 4200)(-2700 4200);
FORCEPROP 2 LAST SIG_NAME M_F_CPU0_SB_DQ<31:0>
J 2
(-2760 4210);
DISPLAY 0.489362 (-2760 4210);
WIRE 17 -1 (-3325 4150)(-3325 4100);
WIRE 17 -1 (-3325 4100)(-3325 4050);
WIRE 17 -1 (-3325 4050)(-3325 4000);
WIRE 17 -1 (-3325 3150)(-3325 3100);
WIRE 17 -1 (-3325 3150)(-3325 3200);
WIRE 17 -1 (-3325 3100)(-3325 3050);
WIRE 17 -1 (-3325 3050)(-3325 3000);
WIRE 17 -1 (-3325 3200)(-3325 3250);
WIRE 17 -1 (-3325 3250)(-3325 3300);
WIRE 17 -1 (-3325 3000)(-3325 2950);
WIRE 17 -1 (-3325 2950)(-3325 2850);
WIRE 17 -1 (-3325 3300)(-3325 3400);
WIRE 17 -1 (-3325 3450)(-3325 3400);
WIRE 17 -1 (-3325 2850)(-3325 2800);
WIRE 17 -1 (-3325 2800)(-3325 2750);
WIRE 17 -1 (-3325 3500)(-3325 3450);
WIRE 17 -1 (-3325 3550)(-3325 3500);
WIRE 17 -1 (-3325 2750)(-3325 2700);
WIRE 17 -1 (-3325 2650)(-3325 2700);
WIRE 17 -1 (-3325 3600)(-3325 3550);
WIRE 17 -1 (-3325 3650)(-3325 3600);
WIRE 17 -1 (-3325 2600)(-3325 2650);
WIRE 17 -1 (-3325 2550)(-3325 2600);
WIRE 17 -1 (-3325 3700)(-3325 3650);
WIRE 17 -1 (-3325 3750)(-3325 3700);
WIRE 17 -1 (-3325 2500)(-3325 2550);
WIRE 17 -1 (-3325 3850)(-3325 3750);
WIRE 17 -1 (-3325 3900)(-3325 3850);
WIRE 17 -1 (-3325 3950)(-3325 3900);
WIRE 17 -1 (-3325 4000)(-3325 3950);
WIRE 17 -1 (-3325 2400)(-3325 2425);
WIRE 17 -1 (-3325 2400)(-3325 2350);
WIRE 17 -1 (-3325 2425)(-2825 2425);
FORCEPROP 2 LAST SIG_NAME M_F_CPU0_SA_CB<7:0>
J 2
(-2825 2435);
DISPLAY 0.489362 (-2825 2435);
WIRE 17 -1 (-3325 2300)(-3325 2350);
WIRE 17 -1 (-3325 2300)(-3325 2250);
WIRE 17 -1 (-3325 2200)(-3325 2250);
WIRE 17 -1 (-3325 2150)(-3325 2200);
WIRE 17 -1 (-3325 2100)(-3325 2150);
WIRE 17 -1 (-3325 2050)(-3325 2100);
WIRE 17 -1 (-3325 1950)(-3325 1975);
WIRE 17 -1 (-3325 1950)(-3325 1900);
WIRE 17 -1 (-3325 1975)(-2825 1975);
FORCEPROP 2 LAST SIG_NAME M_F_CPU0_SB_CB<7:0>
J 2
(-2825 1985);
DISPLAY 0.489362 (-2825 1985);
WIRE 17 -1 (-3325 1850)(-3325 1900);
WIRE 17 -1 (-3325 1850)(-3325 1800);
WIRE 17 -1 (-3325 1750)(-3325 1800);
WIRE 17 -1 (-3325 1700)(-3325 1750);
WIRE 17 -1 (-3325 1650)(-3325 1700);
WIRE 17 -1 (-3325 1600)(-3325 1650);
WIRE 17 -1 (-5850 5300)(-5850 5200);
WIRE 17 -1 (-5850 5300)(-5850 5400);
WIRE 17 -1 (-5850 5200)(-5850 5100);
WIRE 17 -1 (-5850 5400)(-5850 5500);
WIRE 17 -1 (-5850 5500)(-5850 5600);
WIRE 17 -1 (-5850 5700)(-5850 5600);
WIRE 17 -1 (-5850 5800)(-5850 5700);
WIRE 17 -1 (-5850 5900)(-5850 5800);
WIRE 17 -1 (-5850 6000)(-5850 5900);
WIRE 17 -1 (-5850 6000)(-6650 6000);
FORCEPROP 2 LAST SIG_NAME M_F_CPU0_SA_DQS_DP<9:0>
J 2
(-6085 6010);
DISPLAY 0.489362 (-6085 6010);
WIRE 17 -1 (-6050 5950)(-6050 5850);
FORCEPROP 2 LAST SIG_NAME M_F_CPU0_SA_DQS_DN<9:0>
J 2
(-6085 5960);
DISPLAY 0.489362 (-6085 5960);
WIRE 17 -1 (-6050 5750)(-6050 5650);
WIRE 17 -1 (-6050 5850)(-6050 5750);
WIRE 17 -1 (-6050 5650)(-6050 5550);
WIRE 17 -1 (-6050 5450)(-6050 5550);
WIRE 17 -1 (-6050 5350)(-6050 5450);
WIRE 17 -1 (-6050 5250)(-6050 5350);
WIRE 17 -1 (-6050 5250)(-6050 5150);
WIRE 17 -1 (-6050 5150)(-6050 5050);
WIRE 17 -1 (-6050 4300)(-6050 4400);
WIRE 17 -1 (-6050 4200)(-6050 4300);
WIRE 17 -1 (-6050 4400)(-6050 4500);
WIRE 17 -1 (-6050 4600)(-6050 4500);
WIRE 17 -1 (-6050 4200)(-6050 4100);
WIRE 17 -1 (-6050 4100)(-6050 4000);
WIRE 17 -1 (-6050 4700)(-6050 4600);
WIRE 17 -1 (-6050 4800)(-6050 4700);
WIRE 17 -1 (-6050 4900)(-6050 4800);
FORCEPROP 2 LAST SIG_NAME M_F_CPU0_SB_DQS_DN<9:0>
J 2
(-6085 4910);
DISPLAY 0.489362 (-6085 4910);
WIRE 17 -1 (-5850 4750)(-5850 4650);
WIRE 17 -1 (-5850 4850)(-5850 4750);
WIRE 17 -1 (-5850 4650)(-5850 4550);
WIRE 17 -1 (-5850 4450)(-5850 4550);
WIRE 17 -1 (-5850 4950)(-5850 4850);
WIRE 17 -1 (-5850 4950)(-6650 4950);
FORCEPROP 2 LAST SIG_NAME M_F_CPU0_SB_DQS_DP<9:0>
J 2
(-6085 4960);
DISPLAY 0.489362 (-6085 4960);
WIRE 17 -1 (-5850 4350)(-5850 4450);
WIRE 17 -1 (-5850 4250)(-5850 4350);
WIRE 17 -1 (-5850 4250)(-5850 4150);
WIRE 17 -1 (-5850 4150)(-5850 4050);
WIRE 17 -1 (-6050 3800)(-6050 3850);
WIRE 17 -1 (-6050 3750)(-6050 3800);
WIRE 17 -1 (-6050 3850)(-6550 3850);
FORCEPROP 2 LAST SIG_NAME M_F_CPU0_SA_CA<6:0>
J 0
(-6550 3860);
DISPLAY 0.489362 (-6550 3860);
WIRE 17 -1 (-6050 3400)(-6050 3450);
WIRE 17 -1 (-6050 3350)(-6050 3400);
WIRE 17 -1 (-6050 3450)(-6550 3450);
FORCEPROP 2 LAST SIG_NAME M_F_CPU0_SB_CA<6:0>
J 0
(-6550 3460);
DISPLAY 0.489362 (-6550 3460);
WIRE 17 -1 (-6050 3700)(-6050 3750);
WIRE 17 -1 (-6050 3300)(-6050 3350);
WIRE 17 -1 (-6050 3650)(-6050 3700);
WIRE 17 -1 (-6050 3600)(-6050 3650);
WIRE 17 -1 (-6050 3550)(-6050 3600);
WIRE 17 -1 (-6050 3250)(-6050 3300);
WIRE 17 -1 (-6050 3200)(-6050 3250);
WIRE 17 -1 (-6050 3150)(-6050 3200);
WIRE 17 -1 (-6050 5950)(-6650 5950);
WIRE 17 -1 (-6050 4900)(-6650 4900);
WIRE 16 -1 (-7750 2125)(-7025 2125);
FORCEPROP 2 LAST SIG_NAME M_F_CPU0_ALERT_N
J 0
(-7710 2135);
DISPLAY 0.489362 (-7710 2135);
WIRE 16 -1 (-6550 1175)(-5450 1175);
FORCEPROP 2 LAST SIG_NAME TP_M_F_CPU0_SA_TEST39F
J 0
(-6535 1185);
DISPLAY 0.489362 (-6535 1185);
FORCEPROP 2 LASTPROP $XRERR UNIQUE?
J 0
(-6790 1175);
DISPLAY 0.638298 (-6790 1175);
PAINT MONO (-6790 1175);
DISPLAY INVISIBLE (-6790 1175);
WIRE 16 -1 (-6825 2125)(-5450 2125);
FORCEPROP 2 LAST SIG_NAME M_F_CPU0_ALERT_R_N
J 0
(-6535 2135);
DISPLAY 0.489362 (-6535 2135);
FORCEPROP 2 LASTPROP $XRERR UNIQUE?
J 0
(-6775 2135);
DISPLAY 0.638298 (-6775 2135);
PAINT MONO (-6775 2135);
DISPLAY INVISIBLE (-6775 2135);
WIRE 16 -1 (-6550 2975)(-5450 2975);
FORCEPROP 2 LAST SIG_NAME M_F_CPU0_CLK_DP<0>
J 0
(-6550 2985);
DISPLAY 0.489362 (-6550 2985);
WIRE 16 -1 (-6550 2925)(-5450 2925);
FORCEPROP 2 LAST SIG_NAME M_F_CPU0_CLK_DN<0>
J 0
(-6550 2935);
DISPLAY 0.489362 (-6550 2935);
WIRE 16 -1 (-6550 2825)(-5450 2825);
FORCEPROP 2 LAST SIG_NAME M_F_CPU0_SA_CS_N<0>
J 0
(-6550 2835);
DISPLAY 0.489362 (-6550 2835);
WIRE 16 -1 (-6550 2775)(-5450 2775);
FORCEPROP 2 LAST SIG_NAME M_F_CPU0_SA_CS_N<1>
J 0
(-6550 2785);
DISPLAY 0.489362 (-6550 2785);
WIRE 16 -1 (-6550 2325)(-5450 2325);
FORCEPROP 2 LAST SIG_NAME M_F_CPU0_SB_RSP<0>
J 0
(-6550 2335);
DISPLAY 0.489362 (-6550 2335);
WIRE 16 -1 (-6550 2675)(-5450 2675);
FORCEPROP 2 LAST SIG_NAME M_F_CPU0_SA_RSP<0>
J 0
(-6550 2685);
DISPLAY 0.489362 (-6550 2685);
WIRE 16 -1 (-6550 2575)(-5450 2575);
FORCEPROP 2 LAST SIG_NAME M_F_CPU0_SA_PAR
J 0
(-6550 2585);
DISPLAY 0.489362 (-6550 2585);
WIRE 16 -1 (-6550 2475)(-5450 2475);
FORCEPROP 2 LAST SIG_NAME M_F_CPU0_SB_CS_N<0>
J 0
(-6550 2485);
DISPLAY 0.489362 (-6550 2485);
WIRE 16 -1 (-6550 2425)(-5450 2425);
FORCEPROP 2 LAST SIG_NAME M_F_CPU0_SB_CS_N<1>
J 0
(-6550 2435);
DISPLAY 0.489362 (-6550 2435);
WIRE 16 -1 (-6550 2225)(-5450 2225);
FORCEPROP 2 LAST SIG_NAME M_F_CPU0_SB_PAR
J 0
(-6550 2235);
DISPLAY 0.489362 (-6550 2235);
WIRE 16 -1 (-6550 2025)(-5450 2025);
FORCEPROP 2 LAST SIG_NAME M_F_CPU0_RESET_N
J 0
(-6550 2035);
DISPLAY 0.489362 (-6550 2035);
WIRE 16 -1 (-5750 4025)(-5450 4025);
WIRE 16 -1 (-5950 3125)(-5450 3125);
WIRE 16 -1 (-5950 3525)(-5450 3525);
WIRE 16 -1 (-5950 3175)(-5450 3175);
WIRE 16 -1 (-5950 3575)(-5450 3575);
WIRE 16 -1 (-5950 3225)(-5450 3225);
WIRE 16 -1 (-5950 3625)(-5450 3625);
WIRE 16 -1 (-5950 3275)(-5450 3275);
WIRE 16 -1 (-5950 3675)(-5450 3675);
WIRE 16 -1 (-5950 3325)(-5450 3325);
WIRE 16 -1 (-5950 3725)(-5450 3725);
WIRE 16 -1 (-5950 3375)(-5450 3375);
WIRE 16 -1 (-5950 3775)(-5450 3775);
WIRE 16 -1 (-5950 3425)(-5450 3425);
WIRE 16 -1 (-5950 3825)(-5450 3825);
WIRE 16 -1 (-5950 3975)(-5450 3975);
WIRE 16 -1 (-5950 4075)(-5450 4075);
WIRE 16 -1 (-5750 4825)(-5450 4825);
WIRE 16 -1 (-5950 4375)(-5450 4375);
WIRE 16 -1 (-5750 4925)(-5450 4925);
WIRE 16 -1 (-5950 4475)(-5450 4475);
WIRE 16 -1 (-5950 5025)(-5450 5025);
WIRE 16 -1 (-5950 4575)(-5450 4575);
WIRE 16 -1 (-5950 4675)(-5450 4675);
WIRE 16 -1 (-5950 4775)(-5450 4775);
WIRE 16 -1 (-5950 4875)(-5450 4875);
WIRE 16 -1 (-5750 4125)(-5450 4125);
WIRE 16 -1 (-5750 4225)(-5450 4225);
WIRE 16 -1 (-5750 4325)(-5450 4325);
WIRE 16 -1 (-5750 4425)(-5450 4425);
WIRE 16 -1 (-5750 4525)(-5450 4525);
WIRE 16 -1 (-5750 5075)(-5450 5075);
WIRE 16 -1 (-5750 4625)(-5450 4625);
WIRE 16 -1 (-5950 4175)(-5450 4175);
WIRE 16 -1 (-5750 4725)(-5450 4725);
WIRE 16 -1 (-5950 4275)(-5450 4275);
WIRE 16 -1 (-5750 5275)(-5450 5275);
WIRE 16 -1 (-5750 5375)(-5450 5375);
WIRE 16 -1 (-5750 5475)(-5450 5475);
WIRE 16 -1 (-5750 5575)(-5450 5575);
WIRE 16 -1 (-5950 5125)(-5450 5125);
WIRE 16 -1 (-5750 5675)(-5450 5675);
WIRE 16 -1 (-5950 5225)(-5450 5225);
WIRE 16 -1 (-5750 5775)(-5450 5775);
WIRE 16 -1 (-5950 5325)(-5450 5325);
WIRE 16 -1 (-5750 5875)(-5450 5875);
WIRE 16 -1 (-5950 5425)(-5450 5425);
WIRE 16 -1 (-5750 5975)(-5450 5975);
WIRE 16 -1 (-5950 5525)(-5450 5525);
WIRE 16 -1 (-5950 5625)(-5450 5625);
WIRE 16 -1 (-5950 5725)(-5450 5725);
WIRE 16 -1 (-5950 5825)(-5450 5825);
WIRE 16 -1 (-5950 5925)(-5450 5925);
WIRE 16 -1 (-5750 5175)(-5450 5175);
WIRE 16 -1 (-3850 1575)(-3425 1575);
WIRE 16 -1 (-3850 1625)(-3425 1625);
WIRE 16 -1 (-3850 1675)(-3425 1675);
WIRE 16 -1 (-3850 1725)(-3425 1725);
WIRE 16 -1 (-3850 1775)(-3425 1775);
WIRE 16 -1 (-3850 1825)(-3425 1825);
WIRE 16 -1 (-3850 2025)(-3425 2025);
WIRE 16 -1 (-3850 1875)(-3425 1875);
WIRE 16 -1 (-3850 1925)(-3425 1925);
WIRE 16 -1 (-3850 2575)(-3425 2575);
WIRE 16 -1 (-3850 2625)(-3425 2625);
WIRE 16 -1 (-3850 2675)(-3425 2675);
WIRE 16 -1 (-3850 2725)(-3425 2725);
WIRE 16 -1 (-3850 2775)(-3425 2775);
WIRE 16 -1 (-3850 2825)(-3425 2825);
WIRE 16 -1 (-3850 2925)(-3425 2925);
WIRE 16 -1 (-3850 2975)(-3425 2975);
WIRE 16 -1 (-3850 3025)(-3425 3025);
WIRE 16 -1 (-3850 2075)(-3425 2075);
WIRE 16 -1 (-3850 2475)(-3425 2475);
WIRE 16 -1 (-3850 2125)(-3425 2125);
WIRE 16 -1 (-3850 2525)(-3425 2525);
WIRE 16 -1 (-3850 2175)(-3425 2175);
WIRE 16 -1 (-3850 2225)(-3425 2225);
WIRE 16 -1 (-3850 2275)(-3425 2275);
WIRE 16 -1 (-3850 2325)(-3425 2325);
WIRE 16 -1 (-3850 2375)(-3425 2375);
WIRE 16 -1 (-3850 3875)(-3425 3875);
WIRE 16 -1 (-3850 3175)(-3425 3175);
WIRE 16 -1 (-3850 3925)(-3425 3925);
WIRE 16 -1 (-3850 3225)(-3425 3225);
WIRE 16 -1 (-3850 3975)(-3425 3975);
WIRE 16 -1 (-3850 3275)(-3425 3275);
WIRE 16 -1 (-3850 4025)(-3425 4025);
WIRE 16 -1 (-3850 3375)(-3425 3375);
WIRE 16 -1 (-3850 4075)(-3425 4075);
WIRE 16 -1 (-3850 3425)(-3425 3425);
WIRE 16 -1 (-3850 3475)(-3425 3475);
WIRE 16 -1 (-3850 3525)(-3425 3525);
WIRE 16 -1 (-3850 3575)(-3425 3575);
WIRE 16 -1 (-3850 3625)(-3425 3625);
WIRE 16 -1 (-3850 3075)(-3425 3075);
WIRE 16 -1 (-3850 3675)(-3425 3675);
WIRE 16 -1 (-3850 3725)(-3425 3725);
WIRE 16 -1 (-3850 3825)(-3425 3825);
WIRE 16 -1 (-3850 3125)(-3425 3125);
WIRE 16 -1 (-3850 4925)(-3425 4925);
WIRE 16 -1 (-3850 4125)(-3425 4125);
WIRE 16 -1 (-3850 4975)(-3425 4975);
WIRE 16 -1 (-3850 4375)(-3425 4375);
WIRE 16 -1 (-3850 4175)(-3425 4175);
WIRE 16 -1 (-3850 5025)(-3425 5025);
WIRE 16 -1 (-3850 4425)(-3425 4425);
WIRE 16 -1 (-3850 5075)(-3425 5075);
WIRE 16 -1 (-3850 4475)(-3425 4475);
WIRE 16 -1 (-3850 4525)(-3425 4525);
WIRE 16 -1 (-3850 4575)(-3425 4575);
WIRE 16 -1 (-3850 4625)(-3425 4625);
WIRE 16 -1 (-3850 4725)(-3425 4725);
WIRE 16 -1 (-3850 4775)(-3425 4775);
WIRE 16 -1 (-3850 4825)(-3425 4825);
WIRE 16 -1 (-3850 4875)(-3425 4875);
WIRE 16 -1 (-3850 4275)(-3425 4275);
WIRE 16 -1 (-3850 4325)(-3425 4325);
WIRE 16 -1 (-3850 5625)(-3425 5625);
WIRE 16 -1 (-3850 5675)(-3425 5675);
WIRE 16 -1 (-3850 5725)(-3425 5725);
WIRE 16 -1 (-3850 5775)(-3425 5775);
WIRE 16 -1 (-3850 5825)(-3425 5825);
WIRE 16 -1 (-3850 5875)(-3425 5875);
WIRE 16 -1 (-3850 5925)(-3425 5925);
WIRE 16 -1 (-3850 5975)(-3425 5975);
WIRE 16 -1 (-3850 5175)(-3425 5175);
WIRE 16 -1 (-3850 5225)(-3425 5225);
WIRE 16 -1 (-3850 5275)(-3425 5275);
WIRE 16 -1 (-3850 5325)(-3425 5325);
WIRE 16 -1 (-3850 5375)(-3425 5375);
WIRE 16 -1 (-3850 5425)(-3425 5425);
WIRE 16 -1 (-3850 5475)(-3425 5475);
WIRE 16 -1 (-3850 5525)(-3425 5525);
QUIT
